FILE_TYPE = MACRO_DRAWING;
SET COLOR_WIRE YELLOW;
SET COLOR_PROP ORANGE;
SET COLOR_DOT WHITE;
SET COLOR_ARC YELLOW;
SET COLOR_BODY GREEN;
SET COLOR_NOTE PURPLE;
SET PROP_DISPLAY VALUE;
SET PAGE_NUMBER P307;
FORCEADD Q_RES..1
(-75 -950);
FORCEPROP 1 LAST PART_NUMBER CS00002JB13
J 0
(-175 -900);
DISPLAY 0.510638 (-175 -900);
DISPLAY INVISIBLE (-175 -900);
FORCEPROP 1 LAST PACK_TYPE 0402LF
J 0
(-175 -850);
DISPLAY 0.510638 (-175 -850);
FORCEPROP 1 LAST VALUE 0
J 2
(50 -950);
DISPLAY 0.510638 (50 -950);
FORCEPROP 1 LAST MATERIAL EMPTY
J 0
(150 -950);
DISPLAY 0.510638 (150 -950);
PAINT RED (150 -950);
FORCEPROP 1 LAST TOLERANCE 5%
J 0
(75 -950);
DISPLAY 0.510638 (75 -950);
FORCEPROP 1 LAST WATTAGE 1/16W
J 2
(175 -850);
DISPLAY 0.510638 (175 -850);
FORCEPROP 1 LAST $LOCATION R3206
J 0
(-300 -950);
DISPLAY 0.787234 (-300 -950);
FORCEPROP 1 LASTPIN (-175 -950) $PN 1
J 0
(-163 -938);
DISPLAY 0.787234 (-163 -938);
PAINT MONO (-163 -938);
FORCEPROP 1 LASTPIN (25 -950) $PN 2
J 0
(-13 -938);
DISPLAY 0.787234 (-13 -938);
PAINT MONO (-13 -938);
FORCEPROP 1 LAST PATH I12
J 0
(-125 -800);
DISPLAY 0.978723 (-125 -800);
PAINT WHITE (-125 -800);
DISPLAY INVISIBLE (-125 -800);
FORCEPROP 2 LAST CDS_LIB pure_quanta
J 0
(-75 -950);
DISPLAY INVISIBLE (-75 -950);
FORCEPROP 0 LAST CDS_LOCATION R3206
J 0
(175 -825);
DISPLAY 1.021277 (175 -825);
DISPLAY INVISIBLE (175 -825);
FORCEPROP 0 LAST $SEC 1
J 0
(175 -825);
DISPLAY 0.680851 (175 -825);
PAINT MONO (175 -825);
DISPLAY INVISIBLE (175 -825);
FORCEPROP 0 LAST CDS_SEC 1
J 0
(175 -825);
DISPLAY 1.021277 (175 -825);
DISPLAY INVISIBLE (175 -825);
FORCEADD UNIVERSAL_GND..1
(350 -850);
FORCEPROP 3 LASTPIN (350 -800) SIG_NAME GND\g
J 0
(360 -790);
DISPLAY 0.659574 (360 -790);
PAINT MONO (360 -790);
DISPLAY INVISIBLE (360 -790);
FORCEPROP 1 LAST PATH I14
J 0
(425 -850);
DISPLAY 0.872340 (425 -850);
PAINT AQUA (425 -850);
DISPLAY INVISIBLE (425 -850);
FORCEPROP 2 LAST CDS_LIB logical_power
J 0
(350 -850);
PAINT MONO (350 -850);
DISPLAY INVISIBLE (350 -850);
FORCEPROP 1 LAST HDL_POWER GND
J 1
(375 -925);
DISPLAY 0.872340 (375 -925);
PAINT GREEN (375 -925);
DISPLAY INVISIBLE (375 -925);
FORCEADD Q_RES..2
(350 -625);
FORCEPROP 1 LAST PART_NUMBER CS41002FB09
J 0
(390 -750);
DISPLAY 0.638298 (390 -750);
DISPLAY INVISIBLE (390 -750);
FORCEPROP 1 LAST PACK_TYPE 0402LF
J 0
(390 -800);
DISPLAY 0.638298 (390 -800);
FORCEPROP 1 LAST WATTAGE 1/16W
J 0
(390 -650);
DISPLAY 0.638298 (390 -650);
FORCEPROP 1 LAST VALUE 100K
J 0
(395 -550);
DISPLAY 0.638298 (395 -550);
FORCEPROP 1 LAST TOLERANCE 1%
J 0
(395 -600);
DISPLAY 0.638298 (395 -600);
FORCEPROP 1 LAST MATERIAL CHIP
J 0
(390 -700);
DISPLAY 0.638298 (390 -700);
FORCEPROP 1 LAST $LOCATION R3207
J 0
(395 -500);
DISPLAY 0.787234 (395 -500);
FORCEPROP 1 LASTPIN (350 -525) $PN 1
J 0
(355 -563);
DISPLAY 0.787234 (355 -563);
FORCEPROP 1 LASTPIN (350 -725) $PN 2
J 0
(355 -715);
DISPLAY 0.787234 (355 -715);
FORCEPROP 1 LAST PATH I15
J 0
(400 -450);
DISPLAY 0.978723 (400 -450);
PAINT WHITE (400 -450);
DISPLAY INVISIBLE (400 -450);
FORCEPROP 2 LAST CDS_LIB pure_quanta
J 0
(350 -625);
PAINT MONO (350 -625);
DISPLAY INVISIBLE (350 -625);
FORCEPROP 2 LAST CDS_LOCATION R3207
J 0
(400 -400);
DISPLAY 1.021277 (400 -400);
DISPLAY INVISIBLE (400 -400);
FORCEPROP 2 LAST $SEC 1
J 0
(400 -400);
DISPLAY 0.680851 (400 -400);
PAINT MONO (400 -400);
DISPLAY INVISIBLE (400 -400);
FORCEPROP 2 LAST CDS_SEC 1
J 0
(400 -400);
DISPLAY 1.021277 (400 -400);
DISPLAY INVISIBLE (400 -400);
FORCEADD Q_CAP..1
R 2
(-1600 -25);
FORCEPROP 1 LAST PART_NUMBER CH4104K1B00
J 2
(-1650 -175);
DISPLAY 0.510638 (-1650 -175);
DISPLAY INVISIBLE (-1650 -175);
FORCEPROP 1 LAST MATERIAL X7R
J 2
(-1650 -125);
DISPLAY 0.510638 (-1650 -125);
FORCEPROP 1 LAST VOLTAGE 25V
J 2
(-1650 -25);
DISPLAY 0.510638 (-1650 -25);
FORCEPROP 1 LAST PACK_TYPE 0402
J 2
(-1650 -225);
DISPLAY 0.510638 (-1650 -225);
FORCEPROP 1 LAST TOLERANCE 10%
J 2
(-1650 -75);
DISPLAY 0.510638 (-1650 -75);
FORCEPROP 1 LAST VALUE 0.1UF
J 2
(-1650 25);
DISPLAY 0.510638 (-1650 25);
FORCEPROP 1 LAST $LOCATION C1825
J 2
(-1650 75);
DISPLAY 0.978723 (-1650 75);
FORCEPROP 1 LASTPIN (-1600 75) $PN 1
J 2
(-1610 55);
DISPLAY 0.787234 (-1610 55);
FORCEPROP 1 LASTPIN (-1600 -125) $PN 2
J 2
(-1610 -145);
DISPLAY 0.787234 (-1610 -145);
FORCEPROP 1 LAST PATH I17
J 2
(-1650 125);
DISPLAY 0.978723 (-1650 125);
PAINT WHITE (-1650 125);
DISPLAY INVISIBLE (-1650 125);
FORCEPROP 2 LAST CDS_LIB pure_quanta
J 0
(-1600 -25);
PAINT MONO (-1600 -25);
DISPLAY INVISIBLE (-1600 -25);
FORCEPROP 2 LAST CDS_LOCATION C1825
J 0
(-1650 175);
DISPLAY 1.021277 (-1650 175);
DISPLAY INVISIBLE (-1650 175);
FORCEPROP 2 LAST $SEC 1
J 0
(-1650 175);
DISPLAY 0.680851 (-1650 175);
PAINT MONO (-1650 175);
DISPLAY INVISIBLE (-1650 175);
FORCEPROP 2 LAST CDS_SEC 1
J 0
(-1650 175);
DISPLAY 1.021277 (-1650 175);
DISPLAY INVISIBLE (-1650 175);
FORCEADD UNIVERSAL_GND..1
(-1600 -250);
FORCEPROP 3 LASTPIN (-1600 -200) SIG_NAME GND\g
J 0
(-1590 -190);
DISPLAY 0.659574 (-1590 -190);
PAINT MONO (-1590 -190);
DISPLAY INVISIBLE (-1590 -190);
FORCEPROP 1 LAST PATH I18
J 0
(-1525 -250);
DISPLAY 0.872340 (-1525 -250);
PAINT AQUA (-1525 -250);
DISPLAY INVISIBLE (-1525 -250);
FORCEPROP 1 LAST HDL_POWER GND
J 1
(-1575 -325);
DISPLAY 0.872340 (-1575 -325);
PAINT GREEN (-1575 -325);
DISPLAY INVISIBLE (-1575 -325);
FORCEPROP 2 LAST CDS_LIB logical_power
J 0
(-1600 -250);
PAINT MONO (-1600 -250);
DISPLAY INVISIBLE (-1600 -250);
FORCEADD UNIVERSAL_POWER..1
(-1600 250);
FORCEPROP 3 LASTPIN (-1600 200) SIG_NAME P3V3_AUX\g
J 0
(-1590 210);
DISPLAY 0.659574 (-1590 210);
PAINT MONO (-1590 210);
DISPLAY INVISIBLE (-1590 210);
FORCEPROP 1 LAST HDL_POWER P3V3_AUX
J 1
(-1600 300);
DISPLAY 0.872340 (-1600 300);
PAINT GREEN (-1600 300);
FORCEPROP 2 LAST CDS_LIB logical_power
J 0
(-1600 250);
PAINT MONO (-1600 250);
DISPLAY INVISIBLE (-1600 250);
FORCEPROP 1 LAST PATH I19
J 0
(-1550 275);
DISPLAY 0.872340 (-1550 275);
PAINT AQUA (-1550 275);
DISPLAY INVISIBLE (-1550 275);
FORCEADD OFFPAGE..5
(-1175 600);
FORCEPROP 2 LAST $XR0 159 
J 0
(-1430 600);
DISPLAY 0.638298 (-1430 600);
PAINT MONO (-1430 600);
FORCEPROP 1 LAST COMMENT_BODY TRUE
J 0
(-1075 525);
DISPLAY 0.872340 (-1075 525);
PAINT GREEN (-1075 525);
DISPLAY INVISIBLE (-1075 525);
FORCEPROP 1 LAST OFFPAGE TRUE
J 0
(-850 475);
DISPLAY 0.872340 (-850 475);
PAINT GREEN (-850 475);
DISPLAY INVISIBLE (-850 475);
FORCEPROP 2 LAST PATH I20
J 0
(-1425 650);
DISPLAY 1.021277 (-1425 650);
DISPLAY INVISIBLE (-1425 650);
FORCEPROP 2 LAST CDS_LIB standard
J 0
(-1175 600);
PAINT MONO (-1175 600);
DISPLAY INVISIBLE (-1175 600);
FORCEADD OFFPAGE..5
(-1175 750);
FORCEPROP 2 LAST $XR0 159 
J 0
(-1430 750);
DISPLAY 0.638298 (-1430 750);
PAINT MONO (-1430 750);
FORCEPROP 1 LAST COMMENT_BODY TRUE
J 0
(-1075 675);
DISPLAY 0.872340 (-1075 675);
PAINT GREEN (-1075 675);
DISPLAY INVISIBLE (-1075 675);
FORCEPROP 1 LAST OFFPAGE TRUE
J 0
(-850 625);
DISPLAY 0.872340 (-850 625);
PAINT GREEN (-850 625);
DISPLAY INVISIBLE (-850 625);
FORCEPROP 2 LAST CDS_LIB standard
J 0
(-1175 750);
PAINT MONO (-1175 750);
DISPLAY INVISIBLE (-1175 750);
FORCEPROP 2 LAST PATH I21
J 0
(-1425 800);
DISPLAY 1.021277 (-1425 800);
DISPLAY INVISIBLE (-1425 800);
FORCEADD OFFPAGE..5
(-1175 900);
FORCEPROP 2 LAST $XR0 159 
J 0
(-1430 900);
DISPLAY 0.638298 (-1430 900);
PAINT MONO (-1430 900);
FORCEPROP 1 LAST COMMENT_BODY TRUE
J 0
(-1075 825);
DISPLAY 0.872340 (-1075 825);
PAINT GREEN (-1075 825);
DISPLAY INVISIBLE (-1075 825);
FORCEPROP 1 LAST OFFPAGE TRUE
J 0
(-850 775);
DISPLAY 0.872340 (-850 775);
PAINT GREEN (-850 775);
DISPLAY INVISIBLE (-850 775);
FORCEPROP 2 LAST CDS_LIB standard
J 0
(-1175 900);
PAINT MONO (-1175 900);
DISPLAY INVISIBLE (-1175 900);
FORCEPROP 2 LAST PATH I22
J 0
(-1425 950);
DISPLAY 1.021277 (-1425 950);
DISPLAY INVISIBLE (-1425 950);
FORCEADD OFFPAGE..5
(-1175 1050);
FORCEPROP 2 LAST $XR0 159 
J 0
(-1430 1050);
DISPLAY 0.638298 (-1430 1050);
PAINT MONO (-1430 1050);
FORCEPROP 1 LAST COMMENT_BODY TRUE
J 0
(-1075 975);
DISPLAY 0.872340 (-1075 975);
PAINT GREEN (-1075 975);
DISPLAY INVISIBLE (-1075 975);
FORCEPROP 1 LAST OFFPAGE TRUE
J 0
(-850 925);
DISPLAY 0.872340 (-850 925);
PAINT GREEN (-850 925);
DISPLAY INVISIBLE (-850 925);
FORCEPROP 2 LAST CDS_LIB standard
J 0
(-1175 1050);
PAINT MONO (-1175 1050);
DISPLAY INVISIBLE (-1175 1050);
FORCEPROP 2 LAST PATH I23
J 0
(-1425 1100);
DISPLAY 1.021277 (-1425 1100);
DISPLAY INVISIBLE (-1425 1100);
FORCEADD UNIVERSAL_GND..1
(-325 425);
FORCEPROP 3 LASTPIN (-325 475) SIG_NAME GND\g
J 0
(-315 485);
DISPLAY 0.659574 (-315 485);
PAINT MONO (-315 485);
DISPLAY INVISIBLE (-315 485);
FORCEPROP 2 LAST CDS_LIB logical_power
J 0
(-325 425);
PAINT MONO (-325 425);
DISPLAY INVISIBLE (-325 425);
FORCEPROP 1 LAST HDL_POWER GND
J 1
(-300 350);
DISPLAY 0.872340 (-300 350);
PAINT GREEN (-300 350);
DISPLAY INVISIBLE (-300 350);
FORCEPROP 1 LAST PATH I24
J 0
(-250 425);
DISPLAY 0.872340 (-250 425);
PAINT AQUA (-250 425);
DISPLAY INVISIBLE (-250 425);
FORCEADD UNIVERSAL_GND..1
(-525 1150);
FORCEPROP 3 LASTPIN (-525 1200) SIG_NAME GND\g
J 0
(-515 1210);
DISPLAY 0.659574 (-515 1210);
PAINT MONO (-515 1210);
DISPLAY INVISIBLE (-515 1210);
FORCEPROP 1 LAST HDL_POWER GND
J 1
(-500 1075);
DISPLAY 0.872340 (-500 1075);
PAINT GREEN (-500 1075);
DISPLAY INVISIBLE (-500 1075);
FORCEPROP 2 LAST CDS_LIB logical_power
J 0
(-525 1150);
PAINT MONO (-525 1150);
DISPLAY INVISIBLE (-525 1150);
FORCEPROP 1 LAST PATH I25
J 0
(-450 1150);
DISPLAY 0.872340 (-450 1150);
PAINT AQUA (-450 1150);
DISPLAY INVISIBLE (-450 1150);
FORCEADD UNIVERSAL_POWER..1
(-325 1700);
FORCEPROP 3 LASTPIN (-325 1650) SIG_NAME P3V3_AUX\g
J 0
(-315 1660);
DISPLAY 0.659574 (-315 1660);
PAINT MONO (-315 1660);
DISPLAY INVISIBLE (-315 1660);
FORCEPROP 1 LAST HDL_POWER P3V3_AUX
J 1
(-325 1750);
DISPLAY 0.872340 (-325 1750);
PAINT GREEN (-325 1750);
FORCEPROP 2 LAST CDS_LIB logical_power
J 0
(-325 1700);
PAINT MONO (-325 1700);
DISPLAY INVISIBLE (-325 1700);
FORCEPROP 1 LAST PATH I26
J 0
(-275 1725);
DISPLAY 0.872340 (-275 1725);
PAINT AQUA (-275 1725);
DISPLAY INVISIBLE (-275 1725);
FORCEADD OFFPAGE..1
(-1175 2175);
FORCEPROP 2 LAST $XR0 159 
J 0
(-1457 2175);
DISPLAY 0.638298 (-1457 2175);
PAINT MONO (-1457 2175);
FORCEPROP 2 LAST CDS_LIB standard
J 0
(-1175 2175);
PAINT MONO (-1175 2175);
DISPLAY INVISIBLE (-1175 2175);
FORCEPROP 1 LAST OFFPAGE TRUE
J 0
(-850 2050);
DISPLAY 0.872340 (-850 2050);
PAINT GREEN (-850 2050);
DISPLAY INVISIBLE (-850 2050);
FORCEPROP 1 LAST COMMENT_BODY TRUE
J 0
(-1050 2075);
DISPLAY 0.872340 (-1050 2075);
PAINT GREEN (-1050 2075);
DISPLAY INVISIBLE (-1050 2075);
FORCEPROP 2 LAST PATH I27
J 0
(-1450 2225);
DISPLAY 1.021277 (-1450 2225);
DISPLAY INVISIBLE (-1450 2225);
FORCEADD OFFPAGE..1
(-1175 2025);
FORCEPROP 2 LAST $XR0 159 
J 0
(-1457 2025);
DISPLAY 0.638298 (-1457 2025);
PAINT MONO (-1457 2025);
FORCEPROP 2 LAST CDS_LIB standard
J 0
(-1175 2025);
PAINT MONO (-1175 2025);
DISPLAY INVISIBLE (-1175 2025);
FORCEPROP 1 LAST OFFPAGE TRUE
J 0
(-850 1900);
DISPLAY 0.872340 (-850 1900);
PAINT GREEN (-850 1900);
DISPLAY INVISIBLE (-850 1900);
FORCEPROP 1 LAST COMMENT_BODY TRUE
J 0
(-1050 1925);
DISPLAY 0.872340 (-1050 1925);
PAINT GREEN (-1050 1925);
DISPLAY INVISIBLE (-1050 1925);
FORCEPROP 2 LAST PATH I28
J 0
(-1450 2075);
DISPLAY 1.021277 (-1450 2075);
DISPLAY INVISIBLE (-1450 2075);
FORCEADD OFFPAGE..1
(-1175 2325);
FORCEPROP 2 LAST $XR0 159 
J 0
(-1457 2325);
DISPLAY 0.638298 (-1457 2325);
PAINT MONO (-1457 2325);
FORCEPROP 2 LAST CDS_LIB standard
J 0
(-1175 2325);
PAINT MONO (-1175 2325);
DISPLAY INVISIBLE (-1175 2325);
FORCEPROP 1 LAST OFFPAGE TRUE
J 0
(-850 2200);
DISPLAY 0.872340 (-850 2200);
PAINT GREEN (-850 2200);
DISPLAY INVISIBLE (-850 2200);
FORCEPROP 1 LAST COMMENT_BODY TRUE
J 0
(-1050 2225);
DISPLAY 0.872340 (-1050 2225);
PAINT GREEN (-1050 2225);
DISPLAY INVISIBLE (-1050 2225);
FORCEPROP 2 LAST PATH I29
J 0
(-1450 2375);
DISPLAY 1.021277 (-1450 2375);
DISPLAY INVISIBLE (-1450 2375);
FORCEADD OFFPAGE..1
(-2550 -375);
FORCEPROP 2 LAST $XR1 213 
J 0
(-2922 -375);
DISPLAY 0.638298 (-2922 -375);
PAINT MONO (-2922 -375);
FORCEPROP 2 LAST $XR0 159 
J 0
(-2802 -375);
DISPLAY 0.638298 (-2802 -375);
PAINT MONO (-2802 -375);
FORCEPROP 2 LAST PATH I3
J 0
(-2800 -325);
DISPLAY 1.021277 (-2800 -325);
DISPLAY INVISIBLE (-2800 -325);
FORCEPROP 2 LAST CDS_LIB standard
J 0
(-2550 -375);
PAINT MONO (-2550 -375);
DISPLAY INVISIBLE (-2550 -375);
FORCEPROP 1 LAST COMMENT_BODY TRUE
J 0
(-2425 -475);
DISPLAY 0.872340 (-2425 -475);
PAINT GREEN (-2425 -475);
DISPLAY INVISIBLE (-2425 -475);
FORCEPROP 1 LAST OFFPAGE TRUE
J 0
(-2225 -500);
DISPLAY 0.872340 (-2225 -500);
PAINT GREEN (-2225 -500);
DISPLAY INVISIBLE (-2225 -500);
FORCEADD OFFPAGE..1
(-1175 2475);
FORCEPROP 2 LAST $XR0 159 
J 0
(-1457 2475);
DISPLAY 0.638298 (-1457 2475);
PAINT MONO (-1457 2475);
FORCEPROP 1 LAST COMMENT_BODY TRUE
J 0
(-1050 2375);
DISPLAY 0.872340 (-1050 2375);
PAINT GREEN (-1050 2375);
DISPLAY INVISIBLE (-1050 2375);
FORCEPROP 1 LAST OFFPAGE TRUE
J 0
(-850 2350);
DISPLAY 0.872340 (-850 2350);
PAINT GREEN (-850 2350);
DISPLAY INVISIBLE (-850 2350);
FORCEPROP 2 LAST CDS_LIB standard
J 0
(-1175 2475);
PAINT MONO (-1175 2475);
DISPLAY INVISIBLE (-1175 2475);
FORCEPROP 2 LAST PATH I30
J 0
(-1450 2525);
DISPLAY 1.021277 (-1450 2525);
DISPLAY INVISIBLE (-1450 2525);
FORCEADD UNIVERSAL_GND..1
(-325 1850);
FORCEPROP 3 LASTPIN (-325 1900) SIG_NAME GND\g
J 0
(-315 1910);
DISPLAY 0.659574 (-315 1910);
PAINT MONO (-315 1910);
DISPLAY INVISIBLE (-315 1910);
FORCEPROP 1 LAST HDL_POWER GND
J 1
(-300 1775);
DISPLAY 0.872340 (-300 1775);
PAINT GREEN (-300 1775);
DISPLAY INVISIBLE (-300 1775);
FORCEPROP 2 LAST CDS_LIB logical_power
J 0
(-325 1850);
PAINT MONO (-325 1850);
DISPLAY INVISIBLE (-325 1850);
FORCEPROP 1 LAST PATH I31
J 0
(-250 1850);
DISPLAY 0.872340 (-250 1850);
PAINT AQUA (-250 1850);
DISPLAY INVISIBLE (-250 1850);
FORCEADD 74CBTLV3126PW..1
R 2
(225 2275);
FORCEPROP 1 LAST PART_NUMBER AL003126K08
J 2
(473 2683);
DISPLAY 0.723404 (473 2683);
PAINT GREEN (473 2683);
DISPLAY INVISIBLE (473 2683);
FORCEPROP 2 LAST VALUE 74CBTLV3126PW
J 2
(450 2775);
DISPLAY 1.021277 (450 2775);
FORCEPROP 2 LAST PART_TYPE SMLF
J 2
(450 2825);
DISPLAY 1.021277 (450 2825);
FORCEPROP 1 LAST MATERIAL IC
J 2
(473 2628);
DISPLAY 0.723404 (473 2628);
PAINT GREEN (473 2628);
FORCEPROP 1 LAST $LOCATION U222
J 2
(473 2733);
DISPLAY 0.723404 (473 2733);
PAINT GREEN (473 2733);
FORCEPROP 2 LASTPIN (625 2025) $PN 2
J 0
(635 2035);
DISPLAY 0.808511 (635 2035);
FORCEPROP 2 LASTPIN (-175 2025) $PN 3
J 2
(-185 2035);
DISPLAY 0.808511 (-185 2035);
FORCEPROP 2 LASTPIN (625 1975) $PN 1
J 0
(635 1985);
DISPLAY 0.808511 (635 1985);
FORCEPROP 2 LASTPIN (625 2175) $PN 5
J 0
(635 2185);
DISPLAY 0.808511 (635 2185);
FORCEPROP 2 LASTPIN (-175 2175) $PN 6
J 2
(-185 2185);
DISPLAY 0.808511 (-185 2185);
FORCEPROP 2 LASTPIN (625 2125) $PN 4
J 0
(635 2135);
DISPLAY 0.808511 (635 2135);
FORCEPROP 2 LASTPIN (625 2325) $PN 9
J 0
(635 2335);
DISPLAY 0.808511 (635 2335);
FORCEPROP 2 LASTPIN (-175 2325) $PN 8
J 2
(-185 2335);
DISPLAY 0.808511 (-185 2335);
FORCEPROP 2 LASTPIN (625 2275) $PN 10
J 0
(635 2285);
DISPLAY 0.808511 (635 2285);
FORCEPROP 2 LASTPIN (625 2475) $PN 12
J 0
(635 2485);
DISPLAY 0.808511 (635 2485);
FORCEPROP 2 LASTPIN (-175 2475) $PN 11
J 2
(-185 2485);
DISPLAY 0.808511 (-185 2485);
FORCEPROP 2 LASTPIN (625 2425) $PN 13
J 0
(635 2435);
DISPLAY 0.808511 (635 2435);
FORCEPROP 2 LASTPIN (-175 1975) $PN 7
J 2
(-185 1985);
DISPLAY 0.808511 (-185 1985);
FORCEPROP 2 LASTPIN (-175 2525) $PN 14
J 2
(-185 2535);
DISPLAY 0.808511 (-185 2535);
FORCEPROP 2 LAST CDS_LIB pure_quanta
J 2
(225 2275);
PAINT MONO (225 2275);
DISPLAY INVISIBLE (225 2275);
FORCEPROP 1 LAST NEEDS_NO_SIZE TRUE
J 2
(-25 1965);
DISPLAY 0.723404 (-25 1965);
PAINT GREEN (-25 1965);
DISPLAY INVISIBLE (-25 1965);
FORCEPROP 1 LAST CDS_LMAN_SYM_OUTLINE -250,350,250,-350
J 2
(225 2275);
DISPLAY 0.468085 (225 2275);
PAINT GREEN (225 2275);
DISPLAY INVISIBLE (225 2275);
FORCEPROP 1 LAST PATH I32
J 2
(-25 1925);
DISPLAY 0.723404 (-25 1925);
PAINT GREEN (-25 1925);
DISPLAY INVISIBLE (-25 1925);
FORCEPROP 2 LAST CDS_LOCATION U222
J 0
(450 2875);
DISPLAY 1.021277 (450 2875);
DISPLAY INVISIBLE (450 2875);
FORCEPROP 2 LAST $SEC 1
J 0
(450 2875);
DISPLAY 0.680851 (450 2875);
PAINT MONO (450 2875);
DISPLAY INVISIBLE (450 2875);
FORCEPROP 2 LAST CDS_SEC 1
J 0
(450 2875);
DISPLAY 1.021277 (450 2875);
DISPLAY INVISIBLE (450 2875);
FORCEADD Q_CAP..1
R 2
(-525 2800);
FORCEPROP 1 LAST PART_NUMBER CH4104K1B00
J 2
(-575 2650);
DISPLAY 0.510638 (-575 2650);
DISPLAY INVISIBLE (-575 2650);
FORCEPROP 1 LAST TOLERANCE 10%
J 2
(-575 2750);
DISPLAY 0.510638 (-575 2750);
FORCEPROP 1 LAST MATERIAL X7R
J 2
(-575 2700);
DISPLAY 0.510638 (-575 2700);
FORCEPROP 1 LAST VOLTAGE 25V
J 2
(-575 2800);
DISPLAY 0.510638 (-575 2800);
FORCEPROP 1 LAST VALUE 0.1UF
J 2
(-575 2850);
DISPLAY 0.510638 (-575 2850);
FORCEPROP 1 LAST PACK_TYPE 0402
J 2
(-575 2600);
DISPLAY 0.510638 (-575 2600);
FORCEPROP 1 LAST $LOCATION C1826
J 2
(-575 2900);
DISPLAY 0.978723 (-575 2900);
FORCEPROP 1 LASTPIN (-525 2900) $PN 1
J 2
(-535 2880);
DISPLAY 0.787234 (-535 2880);
FORCEPROP 1 LASTPIN (-525 2700) $PN 2
J 2
(-535 2680);
DISPLAY 0.787234 (-535 2680);
FORCEPROP 2 LAST CDS_LIB pure_quanta
J 0
(-525 2800);
PAINT MONO (-525 2800);
DISPLAY INVISIBLE (-525 2800);
FORCEPROP 1 LAST PATH I33
J 2
(-575 2950);
DISPLAY 0.978723 (-575 2950);
PAINT WHITE (-575 2950);
DISPLAY INVISIBLE (-575 2950);
FORCEPROP 2 LAST CDS_LOCATION C1826
J 0
(-575 3000);
DISPLAY 1.021277 (-575 3000);
DISPLAY INVISIBLE (-575 3000);
FORCEPROP 2 LAST $SEC 1
J 0
(-575 3000);
DISPLAY 0.680851 (-575 3000);
PAINT MONO (-575 3000);
DISPLAY INVISIBLE (-575 3000);
FORCEPROP 2 LAST CDS_SEC 1
J 0
(-575 3000);
DISPLAY 1.021277 (-575 3000);
DISPLAY INVISIBLE (-575 3000);
FORCEADD UNIVERSAL_GND..1
(-525 2575);
FORCEPROP 3 LASTPIN (-525 2625) SIG_NAME GND\g
J 0
(-515 2635);
DISPLAY 0.659574 (-515 2635);
PAINT MONO (-515 2635);
DISPLAY INVISIBLE (-515 2635);
FORCEPROP 2 LAST CDS_LIB logical_power
J 0
(-525 2575);
PAINT MONO (-525 2575);
DISPLAY INVISIBLE (-525 2575);
FORCEPROP 1 LAST HDL_POWER GND
J 1
(-500 2500);
DISPLAY 0.872340 (-500 2500);
PAINT GREEN (-500 2500);
DISPLAY INVISIBLE (-500 2500);
FORCEPROP 1 LAST PATH I34
J 0
(-450 2575);
DISPLAY 0.872340 (-450 2575);
PAINT AQUA (-450 2575);
DISPLAY INVISIBLE (-450 2575);
FORCEADD UNIVERSAL_POWER..1
(-325 3125);
FORCEPROP 3 LASTPIN (-325 3075) SIG_NAME P3V3_AUX\g
J 0
(-315 3085);
DISPLAY 0.659574 (-315 3085);
PAINT MONO (-315 3085);
DISPLAY INVISIBLE (-315 3085);
FORCEPROP 1 LAST HDL_POWER P3V3_AUX
J 1
(-325 3175);
DISPLAY 0.872340 (-325 3175);
PAINT GREEN (-325 3175);
FORCEPROP 2 LAST CDS_LIB logical_power
J 0
(-325 3125);
PAINT MONO (-325 3125);
DISPLAY INVISIBLE (-325 3125);
FORCEPROP 1 LAST PATH I35
J 0
(-275 3150);
DISPLAY 0.872340 (-275 3150);
PAINT AQUA (-275 3150);
DISPLAY INVISIBLE (-275 3150);
FORCEADD Q_RES..2
(1800 -2525);
FORCEPROP 1 LAST PART_NUMBER CS11002FB07
J 0
(1840 -2650);
DISPLAY 0.638298 (1840 -2650);
DISPLAY INVISIBLE (1840 -2650);
FORCEPROP 1 LAST MATERIAL CHIP
J 0
(1840 -2600);
DISPLAY 0.638298 (1840 -2600);
FORCEPROP 1 LAST PACK_TYPE 0402LF
J 0
(1850 -2650);
DISPLAY 0.638298 (1850 -2650);
FORCEPROP 1 LAST WATTAGE 1/16W
J 0
(1840 -2550);
DISPLAY 0.638298 (1840 -2550);
FORCEPROP 1 LAST TOLERANCE 1%
J 0
(1845 -2500);
DISPLAY 0.638298 (1845 -2500);
FORCEPROP 1 LAST VALUE 100
J 0
(1845 -2450);
DISPLAY 0.638298 (1845 -2450);
FORCEPROP 1 LAST $LOCATION R3208
J 0
(1845 -2400);
DISPLAY 0.638298 (1845 -2400);
FORCEPROP 1 LASTPIN (1800 -2425) $PN 1
J 0
(1805 -2463);
DISPLAY 0.787234 (1805 -2463);
PAINT MONO (1805 -2463);
FORCEPROP 1 LASTPIN (1800 -2625) $PN 2
J 0
(1805 -2615);
DISPLAY 0.787234 (1805 -2615);
PAINT MONO (1805 -2615);
FORCEPROP 2 LAST CDS_LIB pure_quanta
J 0
(1800 -2525);
DISPLAY INVISIBLE (1800 -2525);
FORCEPROP 1 LAST PATH I37
J 0
(1850 -2350);
DISPLAY 0.978723 (1850 -2350);
PAINT WHITE (1850 -2350);
DISPLAY INVISIBLE (1850 -2350);
FORCEPROP 0 LAST CDS_LOCATION R3208
J 0
(1850 -2350);
DISPLAY 1.021277 (1850 -2350);
DISPLAY INVISIBLE (1850 -2350);
FORCEPROP 0 LAST $SEC 1
J 0
(1850 -2350);
DISPLAY 0.680851 (1850 -2350);
PAINT MONO (1850 -2350);
DISPLAY INVISIBLE (1850 -2350);
FORCEPROP 0 LAST CDS_SEC 1
J 0
(1850 -2350);
DISPLAY 1.021277 (1850 -2350);
DISPLAY INVISIBLE (1850 -2350);
FORCEADD Q_RES..2
(2050 -2525);
FORCEPROP 1 LAST PART_NUMBER CS11002FB07
J 0
(2090 -2650);
DISPLAY 0.638298 (2090 -2650);
DISPLAY INVISIBLE (2090 -2650);
FORCEPROP 1 LAST PACK_TYPE 0402LF
J 0
(2100 -2650);
DISPLAY 0.638298 (2100 -2650);
FORCEPROP 1 LAST WATTAGE 1/16W
J 0
(2090 -2550);
DISPLAY 0.638298 (2090 -2550);
FORCEPROP 1 LAST TOLERANCE 1%
J 0
(2095 -2500);
DISPLAY 0.638298 (2095 -2500);
FORCEPROP 1 LAST VALUE 100
J 0
(2095 -2450);
DISPLAY 0.638298 (2095 -2450);
FORCEPROP 1 LAST MATERIAL CHIP
J 0
(2090 -2600);
DISPLAY 0.638298 (2090 -2600);
FORCEPROP 1 LAST $LOCATION R3216
J 0
(2095 -2400);
DISPLAY 0.638298 (2095 -2400);
FORCEPROP 1 LASTPIN (2050 -2425) $PN 1
J 0
(2055 -2463);
DISPLAY 0.787234 (2055 -2463);
PAINT MONO (2055 -2463);
FORCEPROP 1 LASTPIN (2050 -2625) $PN 2
J 0
(2055 -2615);
DISPLAY 0.787234 (2055 -2615);
PAINT MONO (2055 -2615);
FORCEPROP 2 LAST CDS_LIB pure_quanta
J 0
(2050 -2525);
DISPLAY INVISIBLE (2050 -2525);
FORCEPROP 1 LAST PATH I38
J 0
(2100 -2350);
DISPLAY 0.978723 (2100 -2350);
PAINT WHITE (2100 -2350);
DISPLAY INVISIBLE (2100 -2350);
FORCEPROP 0 LAST CDS_LOCATION R3216
J 0
(2100 -2350);
DISPLAY 1.021277 (2100 -2350);
DISPLAY INVISIBLE (2100 -2350);
FORCEPROP 0 LAST $SEC 1
J 0
(2100 -2350);
DISPLAY 0.680851 (2100 -2350);
PAINT MONO (2100 -2350);
DISPLAY INVISIBLE (2100 -2350);
FORCEPROP 0 LAST CDS_SEC 1
J 0
(2100 -2350);
DISPLAY 1.021277 (2100 -2350);
DISPLAY INVISIBLE (2100 -2350);
FORCEADD UNIVERSAL_GND..1
(1800 -2800);
FORCEPROP 3 LASTPIN (1800 -2750) SIG_NAME GND\g
J 0
(1810 -2740);
DISPLAY 0.659574 (1810 -2740);
PAINT MONO (1810 -2740);
DISPLAY INVISIBLE (1810 -2740);
FORCEPROP 1 LAST HDL_POWER GND
J 1
(1825 -2875);
DISPLAY 0.872340 (1825 -2875);
PAINT GREEN (1825 -2875);
DISPLAY INVISIBLE (1825 -2875);
FORCEPROP 2 LAST CDS_LIB logical_power
J 0
(1800 -2800);
DISPLAY INVISIBLE (1800 -2800);
FORCEPROP 1 LAST PATH I39
J 0
(1875 -2800);
DISPLAY 0.872340 (1875 -2800);
PAINT AQUA (1875 -2800);
DISPLAY INVISIBLE (1875 -2800);
FORCEADD Q_RES..2
(2300 -2525);
FORCEPROP 1 LAST PART_NUMBER CS11002FB07
J 0
(2340 -2650);
DISPLAY 0.638298 (2340 -2650);
DISPLAY INVISIBLE (2340 -2650);
FORCEPROP 1 LAST PACK_TYPE 0402LF
J 0
(2340 -2700);
DISPLAY 0.638298 (2340 -2700);
FORCEPROP 1 LAST WATTAGE 1/16W
J 0
(2340 -2550);
DISPLAY 0.638298 (2340 -2550);
FORCEPROP 1 LAST MATERIAL CHIP
J 0
(2340 -2600);
DISPLAY 0.638298 (2340 -2600);
FORCEPROP 1 LAST VALUE 100
J 0
(2345 -2450);
DISPLAY 0.638298 (2345 -2450);
FORCEPROP 1 LAST TOLERANCE 1%
J 0
(2345 -2500);
DISPLAY 0.638298 (2345 -2500);
FORCEPROP 1 LAST $LOCATION R3217
J 0
(2345 -2400);
DISPLAY 0.638298 (2345 -2400);
FORCEPROP 1 LASTPIN (2300 -2425) $PN 1
J 0
(2305 -2463);
DISPLAY 0.787234 (2305 -2463);
PAINT MONO (2305 -2463);
FORCEPROP 1 LASTPIN (2300 -2625) $PN 2
J 0
(2305 -2615);
DISPLAY 0.787234 (2305 -2615);
PAINT MONO (2305 -2615);
FORCEPROP 2 LAST CDS_LIB pure_quanta
J 0
(2300 -2525);
DISPLAY INVISIBLE (2300 -2525);
FORCEPROP 1 LAST PATH I40
J 0
(2350 -2350);
DISPLAY 0.978723 (2350 -2350);
PAINT WHITE (2350 -2350);
DISPLAY INVISIBLE (2350 -2350);
FORCEPROP 0 LAST CDS_LOCATION R3217
J 0
(2350 -2350);
DISPLAY 1.021277 (2350 -2350);
DISPLAY INVISIBLE (2350 -2350);
FORCEPROP 0 LAST $SEC 1
J 0
(2350 -2350);
DISPLAY 0.680851 (2350 -2350);
PAINT MONO (2350 -2350);
DISPLAY INVISIBLE (2350 -2350);
FORCEPROP 0 LAST CDS_SEC 1
J 0
(2350 -2350);
DISPLAY 1.021277 (2350 -2350);
DISPLAY INVISIBLE (2350 -2350);
FORCEADD OFFPAGE..2
(3325 -2275);
FORCEPROP 2 LAST $XR0 159 
J 0
(3514 -2275);
DISPLAY 0.638298 (3514 -2275);
PAINT MONO (3514 -2275);
FORCEPROP 1 LAST COMMENT_BODY TRUE
J 0
(3280 -2370);
DISPLAY 0.872340 (3280 -2370);
PAINT GREEN (3280 -2370);
DISPLAY INVISIBLE (3280 -2370);
FORCEPROP 1 LAST OFFPAGE TRUE
J 0
(3650 -2400);
DISPLAY 0.872340 (3650 -2400);
PAINT GREEN (3650 -2400);
DISPLAY INVISIBLE (3650 -2400);
FORCEPROP 2 LAST CDS_LIB standard
J 0
(3325 -2275);
PAINT MONO (3325 -2275);
DISPLAY INVISIBLE (3325 -2275);
FORCEPROP 2 LAST PATH I44
J 0
(3525 -2225);
DISPLAY 1.021277 (3525 -2225);
DISPLAY INVISIBLE (3525 -2225);
FORCEADD OFFPAGE..2
(3325 -2125);
FORCEPROP 2 LAST $XR0 159 
J 0
(3514 -2125);
DISPLAY 0.638298 (3514 -2125);
PAINT MONO (3514 -2125);
FORCEPROP 1 LAST COMMENT_BODY TRUE
J 0
(3280 -2220);
DISPLAY 0.872340 (3280 -2220);
PAINT GREEN (3280 -2220);
DISPLAY INVISIBLE (3280 -2220);
FORCEPROP 1 LAST OFFPAGE TRUE
J 0
(3650 -2250);
DISPLAY 0.872340 (3650 -2250);
PAINT GREEN (3650 -2250);
DISPLAY INVISIBLE (3650 -2250);
FORCEPROP 2 LAST CDS_LIB standard
J 0
(3325 -2125);
PAINT MONO (3325 -2125);
DISPLAY INVISIBLE (3325 -2125);
FORCEPROP 2 LAST PATH I45
J 0
(3525 -2075);
DISPLAY 1.021277 (3525 -2075);
DISPLAY INVISIBLE (3525 -2075);
FORCEADD OFFPAGE..2
(3325 -1975);
FORCEPROP 2 LAST $XR0 159 
J 0
(3514 -1975);
DISPLAY 0.638298 (3514 -1975);
PAINT MONO (3514 -1975);
FORCEPROP 1 LAST COMMENT_BODY TRUE
J 0
(3280 -2070);
DISPLAY 0.872340 (3280 -2070);
PAINT GREEN (3280 -2070);
DISPLAY INVISIBLE (3280 -2070);
FORCEPROP 1 LAST OFFPAGE TRUE
J 0
(3650 -2100);
DISPLAY 0.872340 (3650 -2100);
PAINT GREEN (3650 -2100);
DISPLAY INVISIBLE (3650 -2100);
FORCEPROP 2 LAST CDS_LIB standard
J 0
(3325 -1975);
PAINT MONO (3325 -1975);
DISPLAY INVISIBLE (3325 -1975);
FORCEPROP 2 LAST PATH I46
J 0
(3525 -1925);
DISPLAY 1.021277 (3525 -1925);
DISPLAY INVISIBLE (3525 -1925);
FORCEADD Q_RES..1
(1900 600);
FORCEPROP 1 LAST PART_NUMBER CS00002JB13
J 0
(1850 700);
DISPLAY 0.510638 (1850 700);
PAINT WHITE (1850 700);
DISPLAY INVISIBLE (1850 700);
FORCEPROP 1 LAST VALUE 0
J 2
(2050 600);
DISPLAY 0.638298 (2050 600);
FORCEPROP 1 LAST MATERIAL EMPTY
J 0
(2100 600);
DISPLAY 0.638298 (2100 600);
PAINT RED (2100 600);
FORCEPROP 1 LAST $LOCATION R3215
J 0
(1600 600);
DISPLAY 0.702128 (1600 600);
FORCEPROP 1 LAST PATH I56
J 0
(1850 750);
DISPLAY 0.978723 (1850 750);
PAINT WHITE (1850 750);
DISPLAY INVISIBLE (1850 750);
FORCEPROP 2 LAST CDS_LIB pure_quanta
J 0
(1900 600);
DISPLAY INVISIBLE (1900 600);
FORCEPROP 1 LAST PACK_TYPE 0402LF
J 0
(2150 450);
DISPLAY 0.510638 (2150 450);
PAINT SKYBLUE (2150 450);
DISPLAY INVISIBLE (2150 450);
FORCEPROP 1 LAST WATTAGE 1/16W
J 2
(1875 450);
DISPLAY 0.510638 (1875 450);
PAINT SKYBLUE (1875 450);
DISPLAY INVISIBLE (1875 450);
FORCEPROP 1 LAST TOLERANCE 5%
J 0
(1900 500);
DISPLAY 0.510638 (1900 500);
PAINT SKYBLUE (1900 500);
DISPLAY INVISIBLE (1900 500);
FORCEPROP 0 LAST CDS_LOCATION R3215
J 0
(1975 650);
DISPLAY 1.021277 (1975 650);
DISPLAY INVISIBLE (1975 650);
FORCEPROP 0 LAST $SEC 1
J 0
(1975 650);
DISPLAY INVISIBLE (1975 650);
FORCEPROP 0 LAST CDS_SEC 1
J 0
(1975 650);
DISPLAY INVISIBLE (1975 650);
FORCEPROP 1 LASTPIN (1800 600) $PN 1
J 0
(1812 612);
DISPLAY 0.808511 (1812 612);
PAINT WHITE (1812 612);
DISPLAY INVISIBLE (1812 612);
FORCEPROP 1 LASTPIN (2000 600) $PN 2
J 0
(1962 612);
DISPLAY 0.808511 (1962 612);
PAINT WHITE (1962 612);
DISPLAY INVISIBLE (1962 612);
FORCEADD Q_RES..1
(1900 750);
FORCEPROP 1 LAST PART_NUMBER CS00002JB13
J 0
(1850 850);
DISPLAY 0.510638 (1850 850);
PAINT WHITE (1850 850);
DISPLAY INVISIBLE (1850 850);
FORCEPROP 1 LAST MATERIAL EMPTY
J 0
(2100 750);
DISPLAY 0.638298 (2100 750);
PAINT RED (2100 750);
FORCEPROP 1 LAST VALUE 0
J 2
(2050 750);
DISPLAY 0.638298 (2050 750);
FORCEPROP 1 LAST $LOCATION R3214
J 0
(1600 750);
DISPLAY 0.702128 (1600 750);
FORCEPROP 1 LAST PATH I60
J 0
(1850 900);
DISPLAY 0.978723 (1850 900);
PAINT WHITE (1850 900);
DISPLAY INVISIBLE (1850 900);
FORCEPROP 2 LAST CDS_LIB pure_quanta
J 0
(1900 750);
DISPLAY INVISIBLE (1900 750);
FORCEPROP 1 LAST PACK_TYPE 0402LF
J 0
(2150 600);
DISPLAY 0.510638 (2150 600);
PAINT SKYBLUE (2150 600);
DISPLAY INVISIBLE (2150 600);
FORCEPROP 1 LAST WATTAGE 1/16W
J 2
(1875 600);
DISPLAY 0.510638 (1875 600);
PAINT SKYBLUE (1875 600);
DISPLAY INVISIBLE (1875 600);
FORCEPROP 1 LAST TOLERANCE 5%
J 0
(1900 650);
DISPLAY 0.510638 (1900 650);
PAINT SKYBLUE (1900 650);
DISPLAY INVISIBLE (1900 650);
FORCEPROP 0 LAST CDS_LOCATION R3214
J 0
(1975 800);
DISPLAY 1.021277 (1975 800);
DISPLAY INVISIBLE (1975 800);
FORCEPROP 0 LAST $SEC 1
J 0
(1975 800);
DISPLAY INVISIBLE (1975 800);
FORCEPROP 0 LAST CDS_SEC 1
J 0
(1975 800);
DISPLAY INVISIBLE (1975 800);
FORCEPROP 1 LASTPIN (1800 750) $PN 1
J 0
(1812 762);
DISPLAY 0.808511 (1812 762);
PAINT WHITE (1812 762);
DISPLAY INVISIBLE (1812 762);
FORCEPROP 1 LASTPIN (2000 750) $PN 2
J 0
(1962 762);
DISPLAY 0.808511 (1962 762);
PAINT WHITE (1962 762);
DISPLAY INVISIBLE (1962 762);
FORCEADD Q_RES..1
(1900 900);
FORCEPROP 1 LAST PART_NUMBER CS00002JB13
J 0
(1775 975);
DISPLAY 0.510638 (1775 975);
DISPLAY INVISIBLE (1775 975);
FORCEPROP 1 LAST MATERIAL EMPTY
J 0
(2100 900);
DISPLAY 0.638298 (2100 900);
PAINT RED (2100 900);
FORCEPROP 1 LAST VALUE 0
J 2
(2050 900);
DISPLAY 0.638298 (2050 900);
FORCEPROP 1 LAST $LOCATION R3213
J 0
(1600 900);
DISPLAY 0.702128 (1600 900);
FORCEPROP 2 LAST CDS_LIB pure_quanta
J 0
(1900 900);
DISPLAY INVISIBLE (1900 900);
FORCEPROP 1 LAST PATH I61
J 0
(1850 1050);
DISPLAY 0.978723 (1850 1050);
PAINT WHITE (1850 1050);
DISPLAY INVISIBLE (1850 1050);
FORCEPROP 1 LAST TOLERANCE 5%
J 0
(1900 800);
DISPLAY 0.510638 (1900 800);
PAINT SKYBLUE (1900 800);
DISPLAY INVISIBLE (1900 800);
FORCEPROP 1 LAST PACK_TYPE 0402LF
J 0
(2150 750);
DISPLAY 0.510638 (2150 750);
PAINT SKYBLUE (2150 750);
DISPLAY INVISIBLE (2150 750);
FORCEPROP 1 LAST WATTAGE 1/16W
J 2
(1875 750);
DISPLAY 0.510638 (1875 750);
PAINT SKYBLUE (1875 750);
DISPLAY INVISIBLE (1875 750);
FORCEPROP 0 LAST CDS_LOCATION R3213
J 0
(1975 950);
DISPLAY 1.021277 (1975 950);
DISPLAY INVISIBLE (1975 950);
FORCEPROP 0 LAST $SEC 1
J 0
(1975 950);
DISPLAY INVISIBLE (1975 950);
FORCEPROP 0 LAST CDS_SEC 1
J 0
(1975 950);
DISPLAY INVISIBLE (1975 950);
FORCEPROP 1 LASTPIN (1800 900) $PN 1
J 0
(1812 912);
DISPLAY 0.808511 (1812 912);
PAINT WHITE (1812 912);
DISPLAY INVISIBLE (1812 912);
FORCEPROP 1 LASTPIN (2000 900) $PN 2
J 0
(1962 912);
DISPLAY 0.808511 (1962 912);
PAINT WHITE (1962 912);
DISPLAY INVISIBLE (1962 912);
FORCEADD Q_RES..1
(1900 2025);
FORCEPROP 1 LAST PART_NUMBER CS02202FB02
J 0
(1850 2125);
DISPLAY 0.510638 (1850 2125);
PAINT WHITE (1850 2125);
DISPLAY INVISIBLE (1850 2125);
FORCEPROP 1 LAST MATERIAL EMPTY
J 0
(1975 2050);
DISPLAY 0.510638 (1975 2050);
PAINT RED (1975 2050);
FORCEPROP 1 LAST VALUE 22
J 2
(1850 2050);
DISPLAY 0.510638 (1850 2050);
PAINT SKYBLUE (1850 2050);
FORCEPROP 1 LAST $LOCATION R3212
J 0
(1600 2025);
DISPLAY 0.702128 (1600 2025);
PAINT YELLOW (1600 2025);
FORCEPROP 1 LAST PATH I62
J 0
(1850 2175);
DISPLAY 0.978723 (1850 2175);
PAINT WHITE (1850 2175);
DISPLAY INVISIBLE (1850 2175);
FORCEPROP 2 LAST CDS_LIB pure_quanta
J 0
(1900 2025);
DISPLAY INVISIBLE (1900 2025);
FORCEPROP 1 LAST PACK_TYPE 0402LF
J 0
(2150 1875);
DISPLAY 0.510638 (2150 1875);
PAINT SKYBLUE (2150 1875);
DISPLAY INVISIBLE (2150 1875);
FORCEPROP 1 LAST TOLERANCE 1%
J 0
(1900 1925);
DISPLAY 0.510638 (1900 1925);
PAINT SKYBLUE (1900 1925);
DISPLAY INVISIBLE (1900 1925);
FORCEPROP 1 LAST WATTAGE 1/16W
J 2
(1875 1875);
DISPLAY 0.510638 (1875 1875);
PAINT SKYBLUE (1875 1875);
DISPLAY INVISIBLE (1875 1875);
FORCEPROP 0 LAST CDS_LOCATION R3212
J 0
(1975 2075);
DISPLAY 1.021277 (1975 2075);
DISPLAY INVISIBLE (1975 2075);
FORCEPROP 0 LAST $SEC 1
J 0
(1975 2075);
DISPLAY INVISIBLE (1975 2075);
FORCEPROP 0 LAST CDS_SEC 1
J 0
(1975 2075);
DISPLAY INVISIBLE (1975 2075);
FORCEPROP 1 LASTPIN (1800 2025) $PN 1
J 0
(1812 2037);
DISPLAY 0.808511 (1812 2037);
PAINT WHITE (1812 2037);
DISPLAY INVISIBLE (1812 2037);
FORCEPROP 1 LASTPIN (2000 2025) $PN 2
J 0
(1962 2037);
DISPLAY 0.808511 (1962 2037);
PAINT WHITE (1962 2037);
DISPLAY INVISIBLE (1962 2037);
FORCEADD Q_RES..1
(1900 2175);
FORCEPROP 1 LAST PART_NUMBER CS02202FB02
J 0
(1850 2275);
DISPLAY 0.510638 (1850 2275);
PAINT WHITE (1850 2275);
DISPLAY INVISIBLE (1850 2275);
FORCEPROP 1 LAST MATERIAL EMPTY
J 0
(1975 2200);
DISPLAY 0.510638 (1975 2200);
PAINT RED (1975 2200);
FORCEPROP 1 LAST VALUE 22
J 2
(1850 2200);
DISPLAY 0.510638 (1850 2200);
PAINT SKYBLUE (1850 2200);
FORCEPROP 1 LAST $LOCATION R3211
J 0
(1600 2175);
DISPLAY 0.702128 (1600 2175);
PAINT YELLOW (1600 2175);
FORCEPROP 1 LAST PATH I63
J 0
(1850 2325);
DISPLAY 0.978723 (1850 2325);
PAINT WHITE (1850 2325);
DISPLAY INVISIBLE (1850 2325);
FORCEPROP 2 LAST CDS_LIB pure_quanta
J 0
(1900 2175);
DISPLAY INVISIBLE (1900 2175);
FORCEPROP 1 LAST PACK_TYPE 0402LF
J 0
(2150 2025);
DISPLAY 0.510638 (2150 2025);
PAINT SKYBLUE (2150 2025);
DISPLAY INVISIBLE (2150 2025);
FORCEPROP 1 LAST TOLERANCE 1%
J 0
(1900 2075);
DISPLAY 0.510638 (1900 2075);
PAINT SKYBLUE (1900 2075);
DISPLAY INVISIBLE (1900 2075);
FORCEPROP 1 LAST WATTAGE 1/16W
J 2
(1875 2025);
DISPLAY 0.510638 (1875 2025);
PAINT SKYBLUE (1875 2025);
DISPLAY INVISIBLE (1875 2025);
FORCEPROP 0 LAST CDS_LOCATION R3211
J 0
(1975 2225);
DISPLAY 1.021277 (1975 2225);
DISPLAY INVISIBLE (1975 2225);
FORCEPROP 0 LAST $SEC 1
J 0
(1975 2225);
DISPLAY INVISIBLE (1975 2225);
FORCEPROP 0 LAST CDS_SEC 1
J 0
(1975 2225);
DISPLAY INVISIBLE (1975 2225);
FORCEPROP 1 LASTPIN (1800 2175) $PN 1
J 0
(1812 2187);
DISPLAY 0.808511 (1812 2187);
PAINT WHITE (1812 2187);
DISPLAY INVISIBLE (1812 2187);
FORCEPROP 1 LASTPIN (2000 2175) $PN 2
J 0
(1962 2187);
DISPLAY 0.808511 (1962 2187);
PAINT WHITE (1962 2187);
DISPLAY INVISIBLE (1962 2187);
FORCEADD Q_RES..1
(3450 2475);
FORCEPROP 1 LAST PART_NUMBER CS02202FB02
J 0
(3350 2625);
DISPLAY 0.510638 (3350 2625);
PAINT WHITE (3350 2625);
DISPLAY INVISIBLE (3350 2625);
FORCEPROP 1 LAST VALUE 22
J 2
(3400 2500);
DISPLAY 0.510638 (3400 2500);
PAINT SKYBLUE (3400 2500);
FORCEPROP 1 LAST PACK_TYPE 0402LF
J 0
(3475 2575);
DISPLAY 0.510638 (3475 2575);
PAINT SKYBLUE (3475 2575);
FORCEPROP 1 LAST MATERIAL EMPTY
J 0
(3525 2500);
DISPLAY 0.510638 (3525 2500);
PAINT RED (3525 2500);
FORCEPROP 1 LAST WATTAGE 1/16W
J 2
(3450 2575);
DISPLAY 0.510638 (3450 2575);
PAINT SKYBLUE (3450 2575);
FORCEPROP 1 LAST $LOCATION R3209
J 0
(3225 2475);
DISPLAY 0.702128 (3225 2475);
PAINT YELLOW (3225 2475);
FORCEPROP 1 LAST PATH I64
J 0
(3400 2625);
DISPLAY 0.978723 (3400 2625);
PAINT WHITE (3400 2625);
DISPLAY INVISIBLE (3400 2625);
FORCEPROP 1 LAST TOLERANCE 1%
J 0
(3450 2375);
DISPLAY 0.510638 (3450 2375);
PAINT SKYBLUE (3450 2375);
DISPLAY INVISIBLE (3450 2375);
FORCEPROP 2 LAST CDS_LIB pure_quanta
J 0
(3450 2475);
DISPLAY INVISIBLE (3450 2475);
FORCEPROP 0 LAST CDS_LOCATION R3209
J 0
(3350 2650);
DISPLAY 1.021277 (3350 2650);
DISPLAY INVISIBLE (3350 2650);
FORCEPROP 0 LAST $SEC 1
J 0
(3525 2525);
DISPLAY INVISIBLE (3525 2525);
FORCEPROP 0 LAST CDS_SEC 1
J 0
(3525 2525);
DISPLAY INVISIBLE (3525 2525);
FORCEPROP 1 LASTPIN (3350 2475) $PN 1
J 0
(3362 2487);
DISPLAY 0.808511 (3362 2487);
PAINT WHITE (3362 2487);
DISPLAY INVISIBLE (3362 2487);
FORCEPROP 1 LASTPIN (3550 2475) $PN 2
J 0
(3512 2487);
DISPLAY 0.808511 (3512 2487);
PAINT WHITE (3512 2487);
DISPLAY INVISIBLE (3512 2487);
FORCEADD Q_RES..1
(1900 2325);
FORCEPROP 1 LAST PART_NUMBER CS02202FB02
J 0
(1850 2425);
DISPLAY 0.510638 (1850 2425);
PAINT WHITE (1850 2425);
DISPLAY INVISIBLE (1850 2425);
FORCEPROP 1 LAST MATERIAL EMPTY
J 0
(1975 2350);
DISPLAY 0.510638 (1975 2350);
PAINT RED (1975 2350);
FORCEPROP 1 LAST VALUE 22
J 2
(1850 2350);
DISPLAY 0.510638 (1850 2350);
PAINT SKYBLUE (1850 2350);
FORCEPROP 1 LAST $LOCATION R3210
J 0
(1600 2325);
DISPLAY 0.702128 (1600 2325);
PAINT YELLOW (1600 2325);
FORCEPROP 1 LAST PATH I65
J 0
(1850 2475);
DISPLAY 0.978723 (1850 2475);
PAINT WHITE (1850 2475);
DISPLAY INVISIBLE (1850 2475);
FORCEPROP 1 LAST WATTAGE 1/16W
J 2
(1875 2175);
DISPLAY 0.510638 (1875 2175);
PAINT SKYBLUE (1875 2175);
DISPLAY INVISIBLE (1875 2175);
FORCEPROP 1 LAST TOLERANCE 1%
J 0
(1900 2225);
DISPLAY 0.510638 (1900 2225);
PAINT SKYBLUE (1900 2225);
DISPLAY INVISIBLE (1900 2225);
FORCEPROP 1 LAST PACK_TYPE 0402LF
J 0
(2150 2175);
DISPLAY 0.510638 (2150 2175);
PAINT SKYBLUE (2150 2175);
DISPLAY INVISIBLE (2150 2175);
FORCEPROP 2 LAST CDS_LIB pure_quanta
J 0
(1900 2325);
DISPLAY INVISIBLE (1900 2325);
FORCEPROP 0 LAST CDS_LOCATION R3210
J 0
(1975 2375);
DISPLAY 1.021277 (1975 2375);
DISPLAY INVISIBLE (1975 2375);
FORCEPROP 0 LAST $SEC 1
J 0
(1975 2375);
DISPLAY INVISIBLE (1975 2375);
FORCEPROP 0 LAST CDS_SEC 1
J 0
(1975 2375);
DISPLAY INVISIBLE (1975 2375);
FORCEPROP 1 LASTPIN (1800 2325) $PN 1
J 0
(1812 2337);
DISPLAY 0.808511 (1812 2337);
PAINT WHITE (1812 2337);
DISPLAY INVISIBLE (1812 2337);
FORCEPROP 1 LASTPIN (2000 2325) $PN 2
J 0
(1962 2337);
DISPLAY 0.808511 (1962 2337);
PAINT WHITE (1962 2337);
DISPLAY INVISIBLE (1962 2337);
FORCEADD OFFPAGE..4
(2925 600);
FORCEPROP 2 LAST $XR1 240 
J 0
(3231 600);
DISPLAY 0.638298 (3231 600);
PAINT MONO (3231 600);
FORCEPROP 2 LAST $XR0 154 
J 0
(3111 600);
DISPLAY 0.638298 (3111 600);
PAINT MONO (3111 600);
FORCEPROP 1 LAST COMMENT_BODY TRUE
J 0
(2900 500);
DISPLAY 0.872340 (2900 500);
PAINT GREEN (2900 500);
DISPLAY INVISIBLE (2900 500);
FORCEPROP 1 LAST OFFPAGE TRUE
J 0
(3250 475);
DISPLAY 0.872340 (3250 475);
PAINT GREEN (3250 475);
DISPLAY INVISIBLE (3250 475);
FORCEPROP 2 LAST CDS_LIB standard
J 0
(2925 600);
PAINT MONO (2925 600);
DISPLAY INVISIBLE (2925 600);
FORCEPROP 2 LAST PATH I66
J 0
(3250 650);
DISPLAY 1.021277 (3250 650);
DISPLAY INVISIBLE (3250 650);
FORCEADD OFFPAGE..4
(2925 750);
FORCEPROP 2 LAST $XR1 240 
J 0
(3231 750);
DISPLAY 0.638298 (3231 750);
PAINT MONO (3231 750);
FORCEPROP 2 LAST $XR0 154 
J 0
(3111 750);
DISPLAY 0.638298 (3111 750);
PAINT MONO (3111 750);
FORCEPROP 1 LAST COMMENT_BODY TRUE
J 0
(2900 650);
DISPLAY 0.872340 (2900 650);
PAINT GREEN (2900 650);
DISPLAY INVISIBLE (2900 650);
FORCEPROP 1 LAST OFFPAGE TRUE
J 0
(3250 625);
DISPLAY 0.872340 (3250 625);
PAINT GREEN (3250 625);
DISPLAY INVISIBLE (3250 625);
FORCEPROP 2 LAST CDS_LIB standard
J 0
(2925 750);
PAINT MONO (2925 750);
DISPLAY INVISIBLE (2925 750);
FORCEPROP 2 LAST PATH I67
J 0
(3250 800);
DISPLAY 1.021277 (3250 800);
DISPLAY INVISIBLE (3250 800);
FORCEADD OFFPAGE..4
(2925 900);
FORCEPROP 2 LAST $XR1 240 
J 0
(3231 900);
DISPLAY 0.638298 (3231 900);
PAINT MONO (3231 900);
FORCEPROP 2 LAST $XR0 154 
J 0
(3111 900);
DISPLAY 0.638298 (3111 900);
PAINT MONO (3111 900);
FORCEPROP 1 LAST COMMENT_BODY TRUE
J 0
(2900 800);
DISPLAY 0.872340 (2900 800);
PAINT GREEN (2900 800);
DISPLAY INVISIBLE (2900 800);
FORCEPROP 1 LAST OFFPAGE TRUE
J 0
(3250 775);
DISPLAY 0.872340 (3250 775);
PAINT GREEN (3250 775);
DISPLAY INVISIBLE (3250 775);
FORCEPROP 2 LAST CDS_LIB standard
J 0
(2925 900);
PAINT MONO (2925 900);
DISPLAY INVISIBLE (2925 900);
FORCEPROP 2 LAST PATH I68
J 0
(3250 950);
DISPLAY 1.021277 (3250 950);
DISPLAY INVISIBLE (3250 950);
FORCEADD OFFPAGE..4
(4325 1050);
FORCEPROP 2 LAST $XR0 165 
J 0
(4511 1050);
DISPLAY 0.638298 (4511 1050);
PAINT MONO (4511 1050);
FORCEPROP 1 LAST COMMENT_BODY TRUE
J 0
(4300 950);
DISPLAY 0.872340 (4300 950);
PAINT GREEN (4300 950);
DISPLAY INVISIBLE (4300 950);
FORCEPROP 1 LAST OFFPAGE TRUE
J 0
(4650 925);
DISPLAY 0.872340 (4650 925);
PAINT GREEN (4650 925);
DISPLAY INVISIBLE (4650 925);
FORCEPROP 2 LAST CDS_LIB standard
J 0
(4325 1050);
PAINT MONO (4325 1050);
DISPLAY INVISIBLE (4325 1050);
FORCEPROP 2 LAST PATH I69
J 0
(4525 1100);
DISPLAY 1.021277 (4525 1100);
DISPLAY INVISIBLE (4525 1100);
FORCEADD OFFPAGE..2
(2800 2025);
FORCEPROP 2 LAST $XR1 240 
J 0
(3109 2025);
DISPLAY 0.638298 (3109 2025);
PAINT MONO (3109 2025);
FORCEPROP 2 LAST $XR0 154 
J 0
(2989 2025);
DISPLAY 0.638298 (2989 2025);
PAINT MONO (2989 2025);
FORCEPROP 2 LAST PATH I73
J 0
(3125 2075);
DISPLAY 1.021277 (3125 2075);
DISPLAY INVISIBLE (3125 2075);
FORCEPROP 2 LAST CDS_LIB standard
J 0
(2800 2025);
PAINT MONO (2800 2025);
DISPLAY INVISIBLE (2800 2025);
FORCEPROP 1 LAST COMMENT_BODY TRUE
J 0
(2755 1930);
DISPLAY 0.872340 (2755 1930);
PAINT GREEN (2755 1930);
DISPLAY INVISIBLE (2755 1930);
FORCEPROP 1 LAST OFFPAGE TRUE
J 0
(3125 1900);
DISPLAY 0.872340 (3125 1900);
PAINT GREEN (3125 1900);
DISPLAY INVISIBLE (3125 1900);
FORCEADD OFFPAGE..2
(2800 2175);
FORCEPROP 2 LAST $XR1 240 
J 0
(2989 2139);
DISPLAY 0.638298 (2989 2139);
PAINT MONO (2989 2139);
FORCEPROP 2 LAST $XR0 154 
J 0
(2989 2175);
DISPLAY 0.638298 (2989 2175);
PAINT MONO (2989 2175);
FORCEPROP 2 LAST PATH I74
J 0
(3125 2225);
DISPLAY 1.021277 (3125 2225);
DISPLAY INVISIBLE (3125 2225);
FORCEPROP 2 LAST CDS_LIB standard
J 0
(2800 2175);
PAINT MONO (2800 2175);
DISPLAY INVISIBLE (2800 2175);
FORCEPROP 1 LAST OFFPAGE TRUE
J 0
(3125 2050);
DISPLAY 0.872340 (3125 2050);
PAINT GREEN (3125 2050);
DISPLAY INVISIBLE (3125 2050);
FORCEPROP 1 LAST COMMENT_BODY TRUE
J 0
(2755 2080);
DISPLAY 0.872340 (2755 2080);
PAINT GREEN (2755 2080);
DISPLAY INVISIBLE (2755 2080);
FORCEADD OFFPAGE..2
(4300 2475);
FORCEPROP 2 LAST $XR0 165 
J 0
(4489 2475);
DISPLAY 0.638298 (4489 2475);
PAINT MONO (4489 2475);
FORCEPROP 1 LAST COMMENT_BODY TRUE
J 0
(4255 2380);
DISPLAY 0.872340 (4255 2380);
PAINT GREEN (4255 2380);
DISPLAY INVISIBLE (4255 2380);
FORCEPROP 1 LAST OFFPAGE TRUE
J 0
(4625 2350);
DISPLAY 0.872340 (4625 2350);
PAINT GREEN (4625 2350);
DISPLAY INVISIBLE (4625 2350);
FORCEPROP 2 LAST CDS_LIB standard
J 0
(4300 2475);
PAINT MONO (4300 2475);
DISPLAY INVISIBLE (4300 2475);
FORCEPROP 2 LAST PATH I75
J 0
(4500 2525);
DISPLAY 1.021277 (4500 2525);
DISPLAY INVISIBLE (4500 2525);
FORCEADD OFFPAGE..2
(2800 2325);
FORCEPROP 2 LAST $XR1 240 
J 0
(2989 2289);
DISPLAY 0.638298 (2989 2289);
PAINT MONO (2989 2289);
FORCEPROP 2 LAST $XR0 154 
J 0
(2989 2325);
DISPLAY 0.638298 (2989 2325);
PAINT MONO (2989 2325);
FORCEPROP 2 LAST PATH I76
J 0
(3125 2375);
DISPLAY 1.021277 (3125 2375);
DISPLAY INVISIBLE (3125 2375);
FORCEPROP 1 LAST COMMENT_BODY TRUE
J 0
(2755 2230);
DISPLAY 0.872340 (2755 2230);
PAINT GREEN (2755 2230);
DISPLAY INVISIBLE (2755 2230);
FORCEPROP 1 LAST OFFPAGE TRUE
J 0
(3125 2200);
DISPLAY 0.872340 (3125 2200);
PAINT GREEN (3125 2200);
DISPLAY INVISIBLE (3125 2200);
FORCEPROP 2 LAST CDS_LIB standard
J 0
(2800 2325);
PAINT MONO (2800 2325);
DISPLAY INVISIBLE (2800 2325);
FORCEADD Q_CAP..1
R 2
(-525 1375);
FORCEPROP 1 LAST PART_NUMBER CH4104K1B00
J 2
(-575 1225);
DISPLAY 0.510638 (-575 1225);
DISPLAY INVISIBLE (-575 1225);
FORCEPROP 1 LAST TOLERANCE 10%
J 2
(-575 1325);
DISPLAY 0.510638 (-575 1325);
FORCEPROP 1 LAST VOLTAGE 25V
J 2
(-575 1375);
DISPLAY 0.510638 (-575 1375);
FORCEPROP 1 LAST VALUE 0.1UF
J 2
(-575 1425);
DISPLAY 0.510638 (-575 1425);
FORCEPROP 1 LAST MATERIAL X7R
J 2
(-575 1275);
DISPLAY 0.510638 (-575 1275);
FORCEPROP 1 LAST PACK_TYPE 0402
J 2
(-575 1175);
DISPLAY 0.510638 (-575 1175);
FORCEPROP 1 LAST $LOCATION C1827
J 2
(-575 1475);
DISPLAY 0.978723 (-575 1475);
FORCEPROP 1 LASTPIN (-525 1475) $PN 1
J 2
(-535 1455);
DISPLAY 0.787234 (-535 1455);
FORCEPROP 1 LASTPIN (-525 1275) $PN 2
J 2
(-535 1255);
DISPLAY 0.787234 (-535 1255);
FORCEPROP 2 LAST CDS_LIB pure_quanta
J 0
(-525 1375);
PAINT MONO (-525 1375);
DISPLAY INVISIBLE (-525 1375);
FORCEPROP 1 LAST PATH I77
J 2
(-575 1525);
DISPLAY 0.978723 (-575 1525);
PAINT WHITE (-575 1525);
DISPLAY INVISIBLE (-575 1525);
FORCEPROP 2 LAST CDS_LOCATION C1827
J 0
(-575 1575);
DISPLAY 1.021277 (-575 1575);
DISPLAY INVISIBLE (-575 1575);
FORCEPROP 2 LAST $SEC 1
J 0
(-575 1575);
DISPLAY 0.680851 (-575 1575);
PAINT MONO (-575 1575);
DISPLAY INVISIBLE (-575 1575);
FORCEPROP 2 LAST CDS_SEC 1
J 0
(-575 1575);
DISPLAY 1.021277 (-575 1575);
DISPLAY INVISIBLE (-575 1575);
FORCEADD 74CBTLV3126PW..1
R 2
(225 850);
FORCEPROP 1 LAST PART_NUMBER AL003126K08
J 2
(473 1258);
DISPLAY 0.723404 (473 1258);
PAINT GREEN (473 1258);
DISPLAY INVISIBLE (473 1258);
FORCEPROP 2 LAST PART_TYPE SMLF
J 2
(450 1400);
DISPLAY 1.021277 (450 1400);
FORCEPROP 2 LAST VALUE 74CBTLV3126PW
J 2
(450 1350);
DISPLAY 1.021277 (450 1350);
FORCEPROP 1 LAST MATERIAL IC
J 2
(473 1203);
DISPLAY 0.723404 (473 1203);
PAINT GREEN (473 1203);
FORCEPROP 1 LAST $LOCATION U223
J 2
(473 1308);
DISPLAY 0.723404 (473 1308);
PAINT GREEN (473 1308);
FORCEPROP 2 LASTPIN (625 600) $PN 2
J 0
(635 610);
DISPLAY 0.808511 (635 610);
FORCEPROP 2 LASTPIN (-175 600) $PN 3
J 2
(-185 610);
DISPLAY 0.808511 (-185 610);
FORCEPROP 2 LASTPIN (625 550) $PN 1
J 0
(635 560);
DISPLAY 0.808511 (635 560);
FORCEPROP 2 LASTPIN (625 750) $PN 5
J 0
(635 760);
DISPLAY 0.808511 (635 760);
FORCEPROP 2 LASTPIN (-175 750) $PN 6
J 2
(-185 760);
DISPLAY 0.808511 (-185 760);
FORCEPROP 2 LASTPIN (625 700) $PN 4
J 0
(635 710);
DISPLAY 0.808511 (635 710);
FORCEPROP 2 LASTPIN (625 900) $PN 9
J 0
(635 910);
DISPLAY 0.808511 (635 910);
FORCEPROP 2 LASTPIN (-175 900) $PN 8
J 2
(-185 910);
DISPLAY 0.808511 (-185 910);
FORCEPROP 2 LASTPIN (625 850) $PN 10
J 0
(635 860);
DISPLAY 0.808511 (635 860);
FORCEPROP 2 LASTPIN (625 1050) $PN 12
J 0
(635 1060);
DISPLAY 0.808511 (635 1060);
FORCEPROP 2 LASTPIN (-175 1050) $PN 11
J 2
(-185 1060);
DISPLAY 0.808511 (-185 1060);
FORCEPROP 2 LASTPIN (625 1000) $PN 13
J 0
(635 1010);
DISPLAY 0.808511 (635 1010);
FORCEPROP 2 LASTPIN (-175 550) $PN 7
J 2
(-185 560);
DISPLAY 0.808511 (-185 560);
FORCEPROP 2 LASTPIN (-175 1100) $PN 14
J 2
(-185 1110);
DISPLAY 0.808511 (-185 1110);
FORCEPROP 2 LAST CDS_LIB pure_quanta
J 2
(225 850);
PAINT MONO (225 850);
DISPLAY INVISIBLE (225 850);
FORCEPROP 1 LAST NEEDS_NO_SIZE TRUE
J 2
(-25 540);
DISPLAY 0.723404 (-25 540);
PAINT GREEN (-25 540);
DISPLAY INVISIBLE (-25 540);
FORCEPROP 1 LAST CDS_LMAN_SYM_OUTLINE -250,350,250,-350
J 2
(225 850);
DISPLAY 0.468085 (225 850);
PAINT GREEN (225 850);
DISPLAY INVISIBLE (225 850);
FORCEPROP 1 LAST PATH I78
J 2
(-25 500);
DISPLAY 0.723404 (-25 500);
PAINT GREEN (-25 500);
DISPLAY INVISIBLE (-25 500);
FORCEPROP 2 LAST CDS_LOCATION U223
J 0
(450 1450);
DISPLAY 1.021277 (450 1450);
DISPLAY INVISIBLE (450 1450);
FORCEPROP 2 LAST $SEC 1
J 0
(450 1450);
DISPLAY 0.680851 (450 1450);
PAINT MONO (450 1450);
DISPLAY INVISIBLE (450 1450);
FORCEPROP 2 LAST CDS_SEC 1
J 0
(450 1450);
DISPLAY 1.021277 (450 1450);
DISPLAY INVISIBLE (450 1450);
FORCEADD Q_RES..1
R 1
(3275 2275);
FORCEPROP 1 LAST PART_NUMBER CS00002JB13
J 0
(3325 2150);
DISPLAY 0.510638 (3325 2150);
DISPLAY INVISIBLE (3325 2150);
FORCEPROP 1 LAST VALUE 0
J 2
(3375 2275);
DISPLAY 0.638298 (3375 2275);
FORCEPROP 1 LAST MATERIAL CHIP
J 0
(3325 2200);
DISPLAY 0.638298 (3325 2200);
FORCEPROP 1 LAST $LOCATION R3244
J 0
(3325 2225);
DISPLAY 0.978723 (3325 2225);
FORCEPROP 1 LASTPIN (3275 2175) $PN 1
R 1
J 0
(3263 2187);
DISPLAY 0.787234 (3263 2187);
PAINT MONO (3263 2187);
FORCEPROP 1 LASTPIN (3275 2375) $PN 2
R 1
J 0
(3263 2337);
DISPLAY 0.787234 (3263 2337);
PAINT MONO (3263 2337);
FORCEPROP 1 LAST PATH I79
R 1
J 0
(3125 2225);
DISPLAY 0.978723 (3125 2225);
PAINT WHITE (3125 2225);
DISPLAY INVISIBLE (3125 2225);
FORCEPROP 2 LAST CDS_LIB pure_quanta
R 1
J 0
(3275 2275);
DISPLAY INVISIBLE (3275 2275);
FORCEPROP 1 LAST WATTAGE 1/16W
R 1
J 2
(3425 2250);
DISPLAY 0.510638 (3425 2250);
PAINT SKYBLUE (3425 2250);
DISPLAY INVISIBLE (3425 2250);
FORCEPROP 1 LAST PACK_TYPE 0402LF
R 1
J 0
(3425 2525);
DISPLAY 0.510638 (3425 2525);
PAINT SKYBLUE (3425 2525);
DISPLAY INVISIBLE (3425 2525);
FORCEPROP 1 LAST TOLERANCE 5%
R 1
J 0
(3375 2275);
DISPLAY 0.510638 (3375 2275);
PAINT SKYBLUE (3375 2275);
DISPLAY INVISIBLE (3375 2275);
FORCEPROP 0 LAST CDS_LOCATION R3244
R 1
J 0
(3375 2325);
DISPLAY 1.021277 (3375 2325);
DISPLAY INVISIBLE (3375 2325);
FORCEPROP 0 LAST $SEC 1
R 1
J 0
(3375 2325);
DISPLAY 0.680851 (3375 2325);
PAINT MONO (3375 2325);
DISPLAY INVISIBLE (3375 2325);
FORCEPROP 0 LAST CDS_SEC 1
R 1
J 0
(3375 2325);
DISPLAY 1.021277 (3375 2325);
DISPLAY INVISIBLE (3375 2325);
FORCEADD 74LVC1G126SE7..1
(-1300 -425);
FORCEPROP 1 LAST PART_NUMBER AL1G0126009
J 0
(-1194 -741);
DISPLAY 0.723404 (-1194 -741);
PAINT GREEN (-1194 -741);
DISPLAY INVISIBLE (-1194 -741);
FORCEPROP 1 LAST MATERIAL IC
J 0
(-1194 -868);
DISPLAY 0.723404 (-1194 -868);
PAINT GREEN (-1194 -868);
FORCEPROP 2 LAST PART_TYPE SMLF
J 0
(-1175 -250);
DISPLAY 0.638298 (-1175 -250);
FORCEPROP 2 LAST VALUE 74LVC1G126SE-7
J 0
(-1175 -300);
DISPLAY 0.638298 (-1175 -300);
FORCEPROP 1 LAST $LOCATION U286
J 0
(-1194 -594);
DISPLAY 0.723404 (-1194 -594);
PAINT GREEN (-1194 -594);
FORCEPROP 0 LASTPIN (-1550 -375) $PN 2
J 2
(-1560 -365);
DISPLAY 0.680851 (-1560 -365);
PAINT MONO (-1560 -365);
FORCEPROP 0 LASTPIN (-1300 -675) $PN 3
R 1
J 2
(-1310 -685);
DISPLAY 0.680851 (-1310 -685);
PAINT MONO (-1310 -685);
FORCEPROP 0 LASTPIN (-1550 -475) $PN 1
J 2
(-1560 -465);
DISPLAY 0.680851 (-1560 -465);
PAINT MONO (-1560 -465);
FORCEPROP 0 LASTPIN (-1300 -175) $PN 5
R 1
J 0
(-1310 -165);
DISPLAY 0.680851 (-1310 -165);
PAINT MONO (-1310 -165);
FORCEPROP 0 LASTPIN (-1050 -425) $PN 4
J 0
(-1040 -415);
DISPLAY 0.680851 (-1040 -415);
PAINT MONO (-1040 -415);
FORCEPROP 1 LAST NEEDS_NO_SIZE TRUE
J 0
(-1300 -425);
DISPLAY 0.723404 (-1300 -425);
PAINT GREEN (-1300 -425);
DISPLAY INVISIBLE (-1300 -425);
FORCEPROP 1 LAST PATH I80
J 0
(-1300 -425);
DISPLAY 0.723404 (-1300 -425);
PAINT GREEN (-1300 -425);
DISPLAY INVISIBLE (-1300 -425);
FORCEPROP 1 LAST CDS_LMAN_SYM_OUTLINE -100,100,100,-100
J 0
(-1300 -425);
DISPLAY 0.468085 (-1300 -425);
PAINT GREEN (-1300 -425);
DISPLAY INVISIBLE (-1300 -425);
FORCEPROP 2 LAST CDS_LIB pure_quanta
J 0
(-1300 -425);
DISPLAY INVISIBLE (-1300 -425);
FORCEPROP 0 LAST CDS_LOCATION U286
J 0
(-1175 -200);
DISPLAY 1.021277 (-1175 -200);
DISPLAY INVISIBLE (-1175 -200);
FORCEPROP 0 LAST $SEC 1
J 0
(-1175 -200);
DISPLAY 0.680851 (-1175 -200);
PAINT MONO (-1175 -200);
DISPLAY INVISIBLE (-1175 -200);
FORCEPROP 0 LAST CDS_SEC 1
J 0
(-1175 -200);
DISPLAY 1.021277 (-1175 -200);
DISPLAY INVISIBLE (-1175 -200);
FORCEADD Q_RES..1
(-2875 -475);
FORCEPROP 1 LAST PART_NUMBER CS03322FB03
J 0
(-2975 -650);
DISPLAY 0.510638 (-2975 -650);
DISPLAY INVISIBLE (-2975 -650);
FORCEPROP 1 LAST PACK_TYPE 0402LF
J 0
(-2975 -550);
DISPLAY 0.510638 (-2975 -550);
FORCEPROP 1 LAST TOLERANCE 1%
J 0
(-2650 -475);
DISPLAY 0.510638 (-2650 -475);
FORCEPROP 1 LAST VALUE 33.2
J 2
(-2675 -475);
DISPLAY 0.510638 (-2675 -475);
FORCEPROP 1 LAST WATTAGE 1/16W
J 2
(-2700 -625);
DISPLAY 0.510638 (-2700 -625);
FORCEPROP 1 LAST MATERIAL CHIP
J 0
(-2975 -600);
DISPLAY 0.510638 (-2975 -600);
FORCEPROP 1 LAST $LOCATION R3203
J 0
(-3125 -475);
DISPLAY 0.638298 (-3125 -475);
FORCEPROP 1 LASTPIN (-2975 -475) $PN 1
J 0
(-2963 -463);
DISPLAY 0.787234 (-2963 -463);
FORCEPROP 1 LASTPIN (-2775 -475) $PN 2
J 0
(-2813 -463);
DISPLAY 0.787234 (-2813 -463);
FORCEPROP 1 LAST PATH I81
J 0
(-2925 -325);
DISPLAY 0.978723 (-2925 -325);
PAINT WHITE (-2925 -325);
DISPLAY INVISIBLE (-2925 -325);
FORCEPROP 2 LAST CDS_LIB pure_quanta
J 0
(-2875 -475);
PAINT MONO (-2875 -475);
DISPLAY INVISIBLE (-2875 -475);
FORCEPROP 2 LAST CDS_LOCATION R3203
J 0
(-2925 -275);
DISPLAY 1.021277 (-2925 -275);
DISPLAY INVISIBLE (-2925 -275);
FORCEPROP 2 LAST $SEC 1
J 0
(-2925 -275);
DISPLAY 0.680851 (-2925 -275);
PAINT MONO (-2925 -275);
DISPLAY INVISIBLE (-2925 -275);
FORCEPROP 2 LAST CDS_SEC 1
J 0
(-2925 -275);
DISPLAY 1.021277 (-2925 -275);
DISPLAY INVISIBLE (-2925 -275);
FORCEADD OFFPAGE..1
(-3900 -475);
FORCEPROP 2 LAST $XR2 161 
J 0
(-4392 -475);
DISPLAY 0.638298 (-4392 -475);
PAINT MONO (-4392 -475);
FORCEPROP 2 LAST $XR1 164 
J 0
(-4272 -475);
DISPLAY 0.638298 (-4272 -475);
PAINT MONO (-4272 -475);
FORCEPROP 2 LAST $XR0 159 
J 0
(-4152 -475);
DISPLAY 0.638298 (-4152 -475);
PAINT MONO (-4152 -475);
FORCEPROP 2 LAST CDS_LIB standard
J 0
(-3900 -475);
PAINT MONO (-3900 -475);
DISPLAY INVISIBLE (-3900 -475);
FORCEPROP 1 LAST COMMENT_BODY TRUE
J 0
(-3775 -575);
DISPLAY 0.872340 (-3775 -575);
PAINT GREEN (-3775 -575);
DISPLAY INVISIBLE (-3775 -575);
FORCEPROP 1 LAST OFFPAGE TRUE
J 0
(-3575 -600);
DISPLAY 0.872340 (-3575 -600);
PAINT GREEN (-3575 -600);
DISPLAY INVISIBLE (-3575 -600);
FORCEPROP 2 LAST PATH I82
J 0
(-4175 -425);
DISPLAY 1.021277 (-4175 -425);
DISPLAY INVISIBLE (-4175 -425);
FORCEADD UNIVERSAL_GND..1
(-1300 -800);
FORCEPROP 3 LASTPIN (-1300 -750) SIG_NAME GND\g
J 0
(-1290 -740);
DISPLAY 0.659574 (-1290 -740);
PAINT MONO (-1290 -740);
DISPLAY INVISIBLE (-1290 -740);
FORCEPROP 1 LAST PATH I83
J 0
(-1225 -800);
DISPLAY 0.872340 (-1225 -800);
PAINT AQUA (-1225 -800);
DISPLAY INVISIBLE (-1225 -800);
FORCEPROP 2 LAST CDS_LIB logical_power
J 0
(-1300 -800);
PAINT MONO (-1300 -800);
DISPLAY INVISIBLE (-1300 -800);
FORCEPROP 1 LAST HDL_POWER GND
J 1
(-1275 -875);
DISPLAY 0.872340 (-1275 -875);
PAINT GREEN (-1275 -875);
DISPLAY INVISIBLE (-1275 -875);
FORCEADD OFFPAGE..5
R 2
(1075 -425);
FORCEPROP 2 LAST $XR0 161 
J 0
(1264 -425);
DISPLAY 0.638298 (1264 -425);
PAINT MONO (1264 -425);
FORCEPROP 1 LAST OFFPAGE TRUE
J 2
(750 -550);
DISPLAY 0.872340 (750 -550);
PAINT GREEN (750 -550);
DISPLAY INVISIBLE (750 -550);
FORCEPROP 1 LAST COMMENT_BODY TRUE
J 2
(975 -500);
DISPLAY 0.872340 (975 -500);
PAINT GREEN (975 -500);
DISPLAY INVISIBLE (975 -500);
FORCEPROP 2 LAST PATH I84
J 2
(1025 -350);
DISPLAY 1.021277 (1025 -350);
DISPLAY INVISIBLE (1025 -350);
FORCEPROP 2 LAST CDS_LIB standard
J 2
(1075 -425);
DISPLAY INVISIBLE (1075 -425);
FORCEADD Q_RES..1
(-75 -425);
FORCEPROP 1 LAST PART_NUMBER CS04992FB07
J 0
(25 -450);
DISPLAY 0.404255 (25 -450);
DISPLAY INVISIBLE (25 -450);
FORCEPROP 1 LAST MATERIAL CHIP
J 0
(-225 -450);
DISPLAY 0.404255 (-225 -450);
FORCEPROP 1 LAST VALUE 49.9
J 2
(150 -425);
DISPLAY 0.510638 (150 -425);
FORCEPROP 1 LAST LOCATION R3205
J 0
(-325 -425);
DISPLAY 0.808511 (-325 -425);
FORCEPROP 1 LASTPIN (-175 -425) $PN 1
J 0
(-163 -413);
DISPLAY 0.787234 (-163 -413);
PAINT MONO (-163 -413);
FORCEPROP 1 LASTPIN (25 -425) $PN 2
J 0
(-13 -413);
DISPLAY 0.787234 (-13 -413);
PAINT MONO (-13 -413);
FORCEPROP 2 LAST CDS_LIB pure_quanta
J 0
(-75 -425);
DISPLAY INVISIBLE (-75 -425);
FORCEPROP 1 LAST PATH I85
J 0
(-125 -275);
DISPLAY 0.978723 (-125 -275);
PAINT WHITE (-125 -275);
DISPLAY INVISIBLE (-125 -275);
FORCEPROP 1 LAST PACK_TYPE 0402LF
J 0
(225 -425);
DISPLAY 0.510638 (225 -425);
DISPLAY INVISIBLE (225 -425);
FORCEPROP 1 LAST TOLERANCE 1%
J 0
(150 -425);
DISPLAY 0.510638 (150 -425);
DISPLAY INVISIBLE (150 -425);
FORCEPROP 1 LAST WATTAGE 1/16W
J 2
(225 -475);
DISPLAY 0.404255 (225 -475);
DISPLAY INVISIBLE (225 -475);
FORCEPROP 0 LAST $SEC 1
J 0
(-325 -375);
DISPLAY 0.680851 (-325 -375);
PAINT MONO (-325 -375);
DISPLAY INVISIBLE (-325 -375);
FORCEPROP 0 LAST CDS_SEC 1
J 0
(-325 -375);
DISPLAY 1.021277 (-325 -375);
DISPLAY INVISIBLE (-325 -375);
FORCEADD OFFPAGE..1
(-1350 -950);
FORCEPROP 2 LAST $XR0 213 
J 0
(-1602 -950);
DISPLAY 0.638298 (-1602 -950);
PAINT MONO (-1602 -950);
FORCEPROP 1 LAST COMMENT_BODY TRUE
J 0
(-1225 -1050);
DISPLAY 0.872340 (-1225 -1050);
PAINT GREEN (-1225 -1050);
DISPLAY INVISIBLE (-1225 -1050);
FORCEPROP 1 LAST OFFPAGE TRUE
J 0
(-1025 -1075);
DISPLAY 0.872340 (-1025 -1075);
PAINT GREEN (-1025 -1075);
DISPLAY INVISIBLE (-1025 -1075);
FORCEPROP 2 LAST CDS_LIB standard
J 0
(-1350 -950);
DISPLAY INVISIBLE (-1350 -950);
FORCEPROP 2 LAST PATH I9
J 0
(-1600 -900);
DISPLAY 1.021277 (-1600 -900);
DISPLAY INVISIBLE (-1600 -900);
FORCEADD QUANTA_TITLE_BLOCK_C..1
(4625 -3250);
FORCEPROP 0 LAST CDS_CON_LAST_MODIFIED Fri Aug 25 14:02:27 2023
J 0
(2740 -3235);
PAINT MONO (2740 -3235);
DISPLAY INVISIBLE (2740 -3235);
FORCEPROP 2 LAST CUSTOM_TXT_CDS <XR_PAGE_TITLE>
J 0
(-3265 2000);
DISPLAY 0.638298 (-3265 2000);
PAINT PINK (-3265 2000);
DISPLAY INVISIBLE (-3265 2000);
FORCEPROP 2 LAST CUSTOM_TXT_CDS <CON_LAST_MODIFIED>
J 0
(2740 -3235);
DISPLAY 0.978723 (2740 -3235);
FORCEPROP 2 LAST CUSTOM_TXT_CDS <Q_PROJ>
J 0
(2243 -3148);
DISPLAY 1.212766 (2243 -3148);
FORCEPROP 2 LAST CUSTOM_TXT_CDS <Q_REV>
J 0
(4441 -3147);
DISPLAY 1.212766 (4441 -3147);
FORCEPROP 2 LAST CUSTOM_TXT_CDS <NAME_2>
J 0
(1450 -3200);
FORCEPROP 2 LAST CUSTOM_TXT_CDS <Q_NUMBER>
J 0
(3222 -3147);
DISPLAY 1.212766 (3222 -3147);
FORCEPROP 2 LAST CUSTOM_TXT_CDS <NAME_1>
J 0
(1450 -3075);
FORCEPROP 1 LAST CUSTOM_TXT_CDS <CON_PAGE_NUM> OF <CON_TOTAL_PAGES>
J 0
(4179 -3232);
DISPLAY 0.978723 (4179 -3232);
FORCEPROP 1 LAST Q_TITLE PCIE - V3_2 OCP3.0 (2/3)
J 0
(-4741 -3224);
DISPLAY 1.957447 (-4741 -3224);
PAINT GREEN (-4741 -3224);
FORCEPROP 1 LAST Q_DEPT 
J 1
(862 -3201);
DISPLAY 1.957447 (862 -3201);
PAINT GREEN (862 -3201);
FORCEPROP 2 LAST CDS_XR_PAGE_TITLE CR-160 : @S9S_MB_2U_LIB.S9S_MB_2U(SCH_1):PAGE160
J 0
(-3265 2000);
DISPLAY 0.638298 (-3265 2000);
PAINT PINK (-3265 2000);
DISPLAY INVISIBLE (-3265 2000);
FORCEPROP 1 LAST COMMENT_BODY TRUE
J 0
(4637 -3263);
DISPLAY 0.978723 (4637 -3263);
PAINT GREEN (4637 -3263);
DISPLAY INVISIBLE (4637 -3263);
FORCEPROP 2 LAST CDS_LIB pure_quanta
J 0
(4625 -3250);
PAINT MONO (4625 -3250);
DISPLAY INVISIBLE (4625 -3250);
FORCEPROP 1 LAST CDS_LMAN_SYM_OUTLINE -9475,6775,100,-125
J 0
(4625 -3250);
DISPLAY 0.468085 (4625 -3250);
PAINT GREEN (4625 -3250);
DISPLAY INVISIBLE (4625 -3250);
FORCEPROP 2 LAST PAGE_BORDER TRUE
J 0
(-3265 2000);
DISPLAY 0.638298 (-3265 2000);
PAINT PINK (-3265 2000);
DISPLAY INVISIBLE (-3265 2000);
FORCEADD DNS..2
(3475 2475);
PAINT RED (3475 2475);
FORCEPROP 1 LAST COMMENT_BODY TRUE
R 1
J 0
(3550 2250);
DISPLAY 0.872340 (3550 2250);
PAINT GREEN (3550 2250);
DISPLAY INVISIBLE (3550 2250);
FORCEPROP 2 LAST CDS_LIB mstr_misc
J 0
(3475 2475);
DISPLAY INVISIBLE (3475 2475);
FORCEADD DNS..2
(1925 2325);
PAINT RED (1925 2325);
FORCEPROP 2 LAST CDS_LIB mstr_misc
J 0
(1925 2325);
DISPLAY INVISIBLE (1925 2325);
FORCEPROP 1 LAST COMMENT_BODY TRUE
R 1
J 0
(2000 2100);
DISPLAY 0.872340 (2000 2100);
PAINT GREEN (2000 2100);
DISPLAY INVISIBLE (2000 2100);
FORCEADD DNS..2
(1925 2175);
PAINT RED (1925 2175);
FORCEPROP 2 LAST CDS_LIB mstr_misc
J 0
(1925 2175);
DISPLAY INVISIBLE (1925 2175);
FORCEPROP 1 LAST COMMENT_BODY TRUE
R 1
J 0
(2000 1950);
DISPLAY 0.872340 (2000 1950);
PAINT GREEN (2000 1950);
DISPLAY INVISIBLE (2000 1950);
FORCEADD DNS..2
(1925 2025);
PAINT RED (1925 2025);
FORCEPROP 2 LAST CDS_LIB mstr_misc
J 0
(1925 2025);
DISPLAY INVISIBLE (1925 2025);
FORCEPROP 1 LAST COMMENT_BODY TRUE
R 1
J 0
(2000 1800);
DISPLAY 0.872340 (2000 1800);
PAINT GREEN (2000 1800);
DISPLAY INVISIBLE (2000 1800);
FORCEADD DNS..2
(1925 900);
PAINT RED (1925 900);
FORCEPROP 2 LAST CDS_LIB mstr_misc
J 0
(1925 900);
DISPLAY INVISIBLE (1925 900);
FORCEPROP 1 LAST COMMENT_BODY TRUE
R 1
J 0
(2000 675);
DISPLAY 0.872340 (2000 675);
PAINT GREEN (2000 675);
DISPLAY INVISIBLE (2000 675);
FORCEADD DNS..2
(1925 775);
PAINT RED (1925 775);
FORCEPROP 2 LAST CDS_LIB mstr_misc
J 0
(1925 775);
DISPLAY INVISIBLE (1925 775);
FORCEPROP 1 LAST COMMENT_BODY TRUE
R 1
J 0
(2000 550);
DISPLAY 0.872340 (2000 550);
PAINT GREEN (2000 550);
DISPLAY INVISIBLE (2000 550);
FORCEADD DNS..2
(1925 600);
PAINT RED (1925 600);
FORCEPROP 2 LAST CDS_LIB mstr_misc
J 0
(1925 600);
DISPLAY INVISIBLE (1925 600);
FORCEPROP 1 LAST COMMENT_BODY TRUE
R 1
J 0
(2000 375);
DISPLAY 0.872340 (2000 375);
PAINT GREEN (2000 375);
DISPLAY INVISIBLE (2000 375);
FORCEADD DNS..2
(-50 -950);
PAINT RED (-50 -950);
FORCEPROP 1 LAST COMMENT_BODY TRUE
R 1
J 0
(25 -1175);
DISPLAY 0.872340 (25 -1175);
PAINT GREEN (25 -1175);
DISPLAY INVISIBLE (25 -1175);
FORCEPROP 2 LAST CDS_LIB mstr_misc
J 0
(-50 -950);
DISPLAY INVISIBLE (-50 -950);
WIRE 16 -1 (-325 2975)(-325 3075);
WIRE 16 -1 (-325 2525)(-325 2975);
FORCEPROP 0 LAST CDS_PHYS_NET_NAME P3V3_AUX
J 0
(-325 2797);
PAINT MONO (-325 2797);
DISPLAY INVISIBLE (-325 2797);
FORCEPROP 0 LAST VOLTAGE 3.3
J 0
(-325 2750);
PAINT MONO (-325 2750);
DISPLAY INVISIBLE (-325 2750);
FORCEPROP 0 LAST $PHYS_NET_NAME P3V3_AUX
J 0
(-325 2844);
PAINT MONO (-325 2844);
DISPLAY INVISIBLE (-325 2844);
WIRE 16 -1 (-525 2975)(-325 2975);
WIRE 16 -1 (-1600 150)(-1600 200);
WIRE 16 -1 (-1300 150)(-1600 150);
WIRE 16 -1 (-1600 150)(-1600 75);
WIRE 16 -1 (-325 1550)(-325 1650);
WIRE 16 -1 (-325 1100)(-325 1550);
FORCEPROP 0 LAST CDS_PHYS_NET_NAME P3V3_AUX
J 0
(-325 1372);
PAINT MONO (-325 1372);
DISPLAY INVISIBLE (-325 1372);
FORCEPROP 0 LAST VOLTAGE 3.3
J 0
(-325 1325);
PAINT MONO (-325 1325);
DISPLAY INVISIBLE (-325 1325);
FORCEPROP 0 LAST $PHYS_NET_NAME P3V3_AUX
J 0
(-325 1419);
PAINT MONO (-325 1419);
DISPLAY INVISIBLE (-325 1419);
WIRE 16 -1 (-525 1550)(-325 1550);
WIRE 16 -1 (-325 550)(-325 475);
WIRE 16 -1 (-325 550)(-175 550);
FORCEPROP 0 LAST VOLTAGE 0
J 0
(-250 550);
PAINT MONO (-250 550);
DISPLAY INVISIBLE (-250 550);
FORCEPROP 0 LAST CDS_PHYS_NET_NAME GND
J 0
(-250 597);
PAINT MONO (-250 597);
DISPLAY INVISIBLE (-250 597);
WIRE 16 -1 (-525 1275)(-525 1200);
WIRE 16 -1 (-325 1975)(-325 1900);
WIRE 16 -1 (-325 1975)(-175 1975);
FORCEPROP 0 LAST VOLTAGE 0
J 0
(-250 1975);
PAINT MONO (-250 1975);
DISPLAY INVISIBLE (-250 1975);
FORCEPROP 0 LAST CDS_PHYS_NET_NAME GND
J 0
(-250 2022);
PAINT MONO (-250 2022);
DISPLAY INVISIBLE (-250 2022);
WIRE 16 -1 (-525 2700)(-525 2625);
WIRE 16 -1 (-1600 -125)(-1600 -200);
WIRE 16 -1 (-1300 -675)(-1300 -750);
WIRE 16 -1 (1800 -2700)(1800 -2750);
WIRE 16 -1 (1800 -2700)(2050 -2700);
FORCEPROP 0 LAST VOLTAGE 0
J 0
(1925 -2700);
DISPLAY INVISIBLE (1925 -2700);
WIRE 16 -1 (1800 -2625)(1800 -2700);
WIRE 16 -1 (350 -725)(350 -800);
WIRE 16 -1 (-2975 -475)(-3850 -475);
FORCEPROP 0 LAST CDS_PHYS_NET_NAME OCP_V3_2_AUX_PWR_EN
J 0
(-3485 -433);
PAINT MONO (-3485 -433);
DISPLAY INVISIBLE (-3485 -433);
FORCEPROP 2 LAST SIG_NAME OCP_V3_2_AUX_PWR_EN
J 0
(-3760 -465);
DISPLAY 0.680851 (-3760 -465);
PAINT WHITE (-3760 -465);
WIRE 16 -1 (-1050 -425)(-175 -425);
FORCEPROP 2 LAST SIG_NAME FB_BMC_ISOLATE_R2
J 0
(-885 -415);
DISPLAY 0.553191 (-885 -415);
PAINT WHITE (-885 -415);
WIRE 16 -1 (825 -950)(25 -950);
WIRE 16 -1 (350 -525)(350 -425);
WIRE 16 -1 (25 -425)(350 -425);
FORCEPROP 2 LAST SIG_NAME FB_BMC_ISOLATE1
J 0
(340 -415);
DISPLAY 0.553191 (340 -415);
PAINT WHITE (340 -415);
WIRE 16 -1 (350 -425)(825 -425);
WIRE 16 -1 (825 -425)(825 -950);
WIRE 16 -1 (825 -425)(850 -425);
WIRE 16 -1 (850 -425)(1025 -425);
WIRE 16 -1 (850 550)(850 -425);
WIRE 16 -1 (625 550)(850 550);
WIRE 16 -1 (625 700)(850 700);
WIRE 16 -1 (850 700)(850 550);
WIRE 16 -1 (625 850)(850 850);
WIRE 16 -1 (850 850)(850 700);
WIRE 16 -1 (625 1000)(850 1000);
WIRE 16 -1 (850 1000)(850 850);
WIRE 16 -1 (850 1975)(850 1000);
WIRE 16 -1 (625 1975)(850 1975);
WIRE 16 -1 (850 2125)(850 1975);
WIRE 16 -1 (625 2125)(850 2125);
WIRE 16 -1 (625 2275)(850 2275);
WIRE 16 -1 (850 2275)(850 2125);
WIRE 16 -1 (850 2425)(850 2275);
WIRE 16 -1 (625 2425)(850 2425);
WIRE 16 -1 (625 600)(1800 600);
FORCEPROP 2 LAST SIG_NAME NCSI_BMC_TXD1_R1
J 0
(915 610);
DISPLAY 0.680851 (915 610);
PAINT WHITE (915 610);
WIRE 16 -1 (-1300 -950)(-175 -950);
FORCEPROP 2 LAST SIG_NAME FM_NCSI_OCP_V3_2_R_OE
J 0
(-1135 -940);
DISPLAY 0.553191 (-1135 -940);
PAINT WHITE (-1135 -940);
WIRE 16 2175 (-350 -1050)(275 -1050);
WIRE 16 2175 (275 -300)(275 -1050);
WIRE 16 2175 (-350 -300)(-350 -1050);
WIRE 16 2175 (-350 -300)(275 -300);
WIRE 16 -1 (-1550 -475)(-2775 -475);
FORCEPROP 0 LAST CDS_PHYS_NET_NAME OCP_V3_2_AUX_PWR_EN_R1
J 0
(-2410 -433);
PAINT MONO (-2410 -433);
DISPLAY INVISIBLE (-2410 -433);
FORCEPROP 2 LAST SIG_NAME OCP_V3_2_AUX_PWR_EN_R1
J 0
(-2485 -465);
DISPLAY 0.680851 (-2485 -465);
PAINT WHITE (-2485 -465);
WIRE 16 -1 (-1300 -175)(-1300 150);
WIRE 16 -1 (-525 1550)(-525 1475);
WIRE 16 -1 (-325 1100)(-175 1100);
FORCEPROP 0 LAST CDS_PHYS_NET_NAME P3V3_AUX
J 0
(-250 1147);
PAINT MONO (-250 1147);
DISPLAY INVISIBLE (-250 1147);
FORCEPROP 0 LAST VOLTAGE 3.3
J 0
(-250 1100);
PAINT MONO (-250 1100);
DISPLAY INVISIBLE (-250 1100);
FORCEPROP 0 LAST $PHYS_NET_NAME P3V3_AUX
J 0
(-250 1194);
PAINT MONO (-250 1194);
DISPLAY INVISIBLE (-250 1194);
WIRE 16 -1 (-525 2975)(-525 2900);
WIRE 16 -1 (-325 2525)(-175 2525);
FORCEPROP 0 LAST CDS_PHYS_NET_NAME P3V3_AUX
J 0
(-250 2572);
PAINT MONO (-250 2572);
DISPLAY INVISIBLE (-250 2572);
FORCEPROP 0 LAST VOLTAGE 3.3
J 0
(-250 2525);
PAINT MONO (-250 2525);
DISPLAY INVISIBLE (-250 2525);
FORCEPROP 0 LAST $PHYS_NET_NAME P3V3_AUX
J 0
(-250 2619);
PAINT MONO (-250 2619);
DISPLAY INVISIBLE (-250 2619);
WIRE 16 -1 (2050 -2625)(2050 -2700);
WIRE 16 -1 (2050 -2700)(2300 -2700);
WIRE 16 -1 (2300 -2625)(2300 -2700);
WIRE 16 -1 (-2500 -375)(-1550 -375);
FORCEPROP 0 LAST CDS_PHYS_NET_NAME FM_OCP_SFF_PWR_GOOD
J 0
(-2135 -333);
PAINT MONO (-2135 -333);
DISPLAY INVISIBLE (-2135 -333);
FORCEPROP 2 LAST SIG_NAME FM_OCP_V3_2_PWR_GOOD
J 0
(-2360 -365);
DISPLAY 0.680851 (-2360 -365);
PAINT WHITE (-2360 -365);
WIRE 16 2175 (3200 2075)(3900 2075);
WIRE 16 2175 (3900 2675)(3900 2075);
WIRE 16 2175 (3200 2675)(3200 2075);
WIRE 16 2175 (3200 2675)(3900 2675);
FORCEPROP 0 LAST M1 CO-LAYOUT
J 0
(3300 2700);
DISPLAY 1.021277 (3300 2700);
WIRE 16 -1 (4250 2475)(3550 2475);
FORCEPROP 2 LAST SIG_NAME OCP_V3_2_RBT_ARB_IN
J 0
(3665 2485);
DISPLAY 0.680851 (3665 2485);
PAINT WHITE (3665 2485);
WIRE 16 -1 (3275 2475)(625 2475);
FORCEPROP 0 LAST CDS_PHYS_NET_NAME OCP_SFF_RBT_ARB_IN
J 0
(990 2517);
PAINT MONO (990 2517);
DISPLAY INVISIBLE (990 2517);
FORCEPROP 2 LAST SIG_NAME OCP_V3_2_RBT_ARB_IN_R
J 0
(915 2485);
DISPLAY 0.680851 (915 2485);
PAINT WHITE (915 2485);
WIRE 16 -1 (3275 2375)(3275 2475);
WIRE 16 -1 (3275 2475)(3350 2475);
WIRE 16 -1 (-1125 900)(-175 900);
FORCEPROP 2 LAST SIG_NAME NCSI_OCP_V3_2_TX_EN
J 0
(-1060 910);
DISPLAY 0.680851 (-1060 910);
PAINT WHITE (-1060 910);
WIRE 16 -1 (3275 2175)(3275 1050);
WIRE 16 -1 (4275 1050)(3275 1050);
WIRE 16 -1 (625 1050)(3275 1050);
FORCEPROP 2 LAST SIG_NAME OCP_V3_2_RBT_ARB_OUT
J 0
(915 1060);
DISPLAY 0.680851 (915 1060);
PAINT WHITE (915 1060);
WIRE 16 -1 (625 2025)(1800 2025);
FORCEPROP 2 LAST SIG_NAME NCSI_BMC_RXD1_R1
J 0
(915 2035);
DISPLAY 0.680851 (915 2035);
PAINT WHITE (915 2035);
WIRE 16 -1 (2750 2025)(2000 2025);
FORCEPROP 2 LAST SIG_NAME RMII_OCP_BMC_RXD_1
J 0
(2140 2035);
DISPLAY 0.680851 (2140 2035);
PAINT WHITE (2140 2035);
WIRE 16 -1 (625 750)(1800 750);
FORCEPROP 2 LAST SIG_NAME NCSI_BMC_TXD0_R1
J 0
(915 760);
DISPLAY 0.680851 (915 760);
PAINT WHITE (915 760);
WIRE 16 -1 (625 900)(1800 900);
FORCEPROP 2 LAST SIG_NAME NCSI_BMC_TX_EN_R1
J 0
(915 910);
DISPLAY 0.680851 (915 910);
PAINT WHITE (915 910);
WIRE 16 -1 (2875 750)(2000 750);
FORCEPROP 2 LAST SIG_NAME RMII_BMC_OCP_TXD_0
J 0
(2290 760);
DISPLAY 0.680851 (2290 760);
PAINT WHITE (2290 760);
WIRE 16 -1 (2875 600)(2000 600);
FORCEPROP 2 LAST SIG_NAME RMII_BMC_OCP_TXD_1
J 0
(2290 610);
DISPLAY 0.680851 (2290 610);
PAINT WHITE (2290 610);
WIRE 16 -1 (2750 2175)(2000 2175);
FORCEPROP 2 LAST SIG_NAME RMII_OCP_BMC_RXD_0
J 0
(2140 2185);
DISPLAY 0.680851 (2140 2185);
PAINT WHITE (2140 2185);
WIRE 16 -1 (-1125 600)(-175 600);
FORCEPROP 2 LAST SIG_NAME NCSI_OCP_V3_2_TXD1
J 0
(-1060 610);
DISPLAY 0.680851 (-1060 610);
PAINT WHITE (-1060 610);
WIRE 16 -1 (625 2175)(1800 2175);
FORCEPROP 0 LAST CDS_PHYS_NET_NAME NCSI_BMC_RXD0_R
J 0
(690 2217);
PAINT MONO (690 2217);
DISPLAY INVISIBLE (690 2217);
FORCEPROP 2 LAST SIG_NAME NCSI_BMC_RXD0_R1
J 0
(915 2185);
DISPLAY 0.680851 (915 2185);
PAINT WHITE (915 2185);
WIRE 16 -1 (-1125 2175)(-175 2175);
FORCEPROP 0 LAST CDS_PHYS_NET_NAME NCSI_OCP_SFF_RXD0
J 0
(-1060 2217);
PAINT MONO (-1060 2217);
DISPLAY INVISIBLE (-1060 2217);
FORCEPROP 2 LAST SIG_NAME NCSI_OCP_V3_2_RXD0
J 0
(-985 2185);
DISPLAY 0.680851 (-985 2185);
PAINT WHITE (-985 2185);
WIRE 16 -1 (2875 900)(2000 900);
FORCEPROP 2 LAST SIG_NAME RMII_BMC_OCP_TX_EN
J 0
(2290 910);
DISPLAY 0.680851 (2290 910);
PAINT WHITE (2290 910);
WIRE 16 -1 (-1125 2475)(-175 2475);
FORCEPROP 0 LAST CDS_PHYS_NET_NAME OCP_SFF_ISO_RBT_ARB_IN
J 0
(-760 2517);
PAINT MONO (-760 2517);
DISPLAY INVISIBLE (-760 2517);
FORCEPROP 2 LAST SIG_NAME OCP_V3_2_ISO1_RBT_ARB_IN
J 0
(-985 2485);
DISPLAY 0.680851 (-985 2485);
PAINT WHITE (-985 2485);
WIRE 16 -1 (-175 2325)(-1125 2325);
FORCEPROP 0 LAST CDS_PHYS_NET_NAME NCSI_OCP_SFF_CRS_DV
J 0
(-1060 2367);
PAINT MONO (-1060 2367);
DISPLAY INVISIBLE (-1060 2367);
FORCEPROP 2 LAST SIG_NAME NCSI_OCP_V3_2_CRS_DV
J 0
(-985 2335);
DISPLAY 0.680851 (-985 2335);
PAINT WHITE (-985 2335);
WIRE 16 -1 (1800 2325)(625 2325);
FORCEPROP 0 LAST CDS_PHYS_NET_NAME NCSI_BMC_CRS_DV_R
J 0
(690 2367);
PAINT MONO (690 2367);
DISPLAY INVISIBLE (690 2367);
FORCEPROP 2 LAST SIG_NAME NCSI_BMC_CRS_DV_R1
J 0
(915 2335);
DISPLAY 0.680851 (915 2335);
PAINT WHITE (915 2335);
WIRE 16 -1 (-1125 2025)(-175 2025);
FORCEPROP 2 LAST SIG_NAME NCSI_OCP_V3_2_RXD1
J 0
(-985 2035);
DISPLAY 0.680851 (-985 2035);
PAINT WHITE (-985 2035);
WIRE 16 -1 (-1125 1050)(-175 1050);
FORCEPROP 2 LAST SIG_NAME OCP_V3_2_ISO2_RBT_ARB_OUT
J 0
(-1060 1060);
DISPLAY 0.680851 (-1060 1060);
PAINT WHITE (-1060 1060);
WIRE 16 -1 (-1125 750)(-175 750);
FORCEPROP 2 LAST SIG_NAME NCSI_OCP_V3_2_TXD0
J 0
(-1060 760);
DISPLAY 0.680851 (-1060 760);
PAINT WHITE (-1060 760);
WIRE 16 -1 (2300 -2425)(2300 -2275);
WIRE 16 -1 (3275 -2275)(2300 -2275);
FORCEPROP 0 LAST CDS_PHYS_NET_NAME OCP_SFF_ISO_BIF2_EN
J 0
(2365 -2233);
PAINT MONO (2365 -2233);
DISPLAY INVISIBLE (2365 -2233);
FORCEPROP 2 LAST SIG_NAME OCP_V3_2_ISO_BIF2_EN
J 0
(2565 -2265);
DISPLAY 0.680851 (2565 -2265);
PAINT WHITE (2565 -2265);
WIRE 16 -1 (2050 -2425)(2050 -2125);
WIRE 16 -1 (3275 -2125)(2050 -2125);
FORCEPROP 0 LAST CDS_PHYS_NET_NAME OCP_SFF_ISO_BIF1_EN
J 0
(2365 -2083);
PAINT MONO (2365 -2083);
DISPLAY INVISIBLE (2365 -2083);
FORCEPROP 2 LAST SIG_NAME OCP_V3_2_ISO_BIF1_EN
J 0
(2565 -2115);
DISPLAY 0.680851 (2565 -2115);
PAINT WHITE (2565 -2115);
WIRE 16 -1 (1800 -2425)(1800 -1975);
WIRE 16 -1 (3275 -1975)(1800 -1975);
FORCEPROP 0 LAST CDS_PHYS_NET_NAME OCP_SFF_ISO_BIF0_EN
J 0
(2365 -1933);
PAINT MONO (2365 -1933);
DISPLAY INVISIBLE (2365 -1933);
FORCEPROP 2 LAST SIG_NAME OCP_V3_2_ISO_BIF0_EN
J 0
(2565 -1965);
DISPLAY 0.680851 (2565 -1965);
PAINT WHITE (2565 -1965);
WIRE 16 -1 (2750 2325)(2000 2325);
FORCEPROP 2 LAST SIG_NAME RMII_OCP_BMC_CRSDV
J 0
(2140 2335);
DISPLAY 0.680851 (2140 2335);
PAINT WHITE (2140 2335);
DOT 1 (850 550);
DOT 1 (850 700);
DOT 1 (850 850);
DOT 1 (3275 2475);
DOT 1 (1800 -2700);
DOT 1 (2050 -2700);
DOT 1 (-1600 150);
DOT 1 (850 1000);
DOT 1 (850 2125);
DOT 1 (850 2275);
DOT 1 (850 1975);
DOT 1 (-325 2975);
DOT 1 (-325 1550);
DOT 1 (3275 1050);
DOT 1 (350 -425);
DOT 1 (825 -425);
DOT 1 (850 -425);
FORCENOTE
20210824 MODIFY FOR GT
(-3800 3100) 0;
DISPLAY LEFT (-3800 3100);
DISPLAY 2.510638 (-3800 3100);
PAINT PINK (-3800 3100);
FORCENOTE
20220803 POP R3205, DEPOP R3206
(-825 -1150) 0;
DISPLAY LEFT (-825 -1150);
DISPLAY 1.276596 (-825 -1150);
PAINT PINK (-825 -1150);
QUIT
